G04 ================== begin FILE IDENTIFICATION RECORD ==================*
G04 Layout Name:  13948-1b.brd*
G04 Film Name:    NOTICE*
G04 File Format:  Gerber RS274X*
G04 File Origin:  Cadence Allegro 16.5-S045*
G04 Origin Date:  Thu Nov 13 15:46:03 2014*
G04 *
G04 Layer:  MANUFACTURING/THERMAL*
G04 *
G04 Offset:    (0.00 0.00)*
G04 Mirror:    No*
G04 Mode:      Positive*
G04 Rotation:  0*
G04 FullContactRelief:  No*
G04 UndefLineWidth:     6.00*
G04 ================== end FILE IDENTIFICATION RECORD ====================*
%FSLAX35Y35*MOIN*%
%IR0*IPPOS*OFA0.00000B0.00000*MIA0B0*SFA1.00000B1.00000*%
%ADD10C,.02*%
%ADD11C,.015*%
%ADD12C,.006*%
G75*
%LPD*%
G75*
G36*
G01X123678Y723362D02*
G02X102132Y744908I7501J29047D01*
G01X96992Y744909D01*
G03X123679Y718222I34187J7500D01*
G01X123678Y723362D01*
G37*
G36*
G01X102132Y759909D02*
G02X123678Y781456I29047J-7500D01*
G01X123679Y786596D01*
G03X96992Y759908I7500J-34187D01*
G01X102132Y759909D01*
G37*
G36*
G01X160226Y744908D02*
G02X138679Y723362I-29047J7501D01*
G01X138678Y718222D01*
G03X165366Y744909I-7499J34187D01*
G01X160226Y744908D01*
G37*
G36*
G01X138679Y781456D02*
G02X160226Y759909I-7500J-29047D01*
G01X165366Y759908D01*
G03X138678Y786596I-34187J-7499D01*
G01X138679Y781456D01*
G37*
G36*
G01X178549Y273290D02*
G02X150990Y310847I11812J37557D01*
G01Y326595D01*
X156895D01*
Y310847D01*
G03X178549Y279536I33464J0D01*
G01Y273290D01*
G37*
G36*
G01X150990Y365965D02*
Y381713D01*
G02X178549Y419270I39371J0D01*
G01Y413024D01*
G03X156895Y381713I11810J-31311D01*
G01Y365965D01*
X150990D01*
G37*
G36*
G01X202171Y273290D02*
Y279536D01*
G03X223825Y310847I-11810J31311D01*
G01Y326595D01*
X229730D01*
Y310847D01*
G02X202171Y273290I-39371J0D01*
G37*
G36*
G01X223825Y365965D02*
Y381713D01*
G03X202171Y413024I-33464J0D01*
G01Y419270D01*
G02X229730Y381713I-11812J-37557D01*
G01Y365965D01*
X223825D01*
G37*
G54D10*
G01X-41340Y92780D02*
Y103405D01*
X-40923Y104446D01*
X-40090Y105072D01*
X-38840Y105280D01*
X-37590Y104863D01*
X-36965Y103822D01*
G01X-39465Y100280D02*
X-43632D01*
G01X-24590Y92780D02*
X-25840Y92988D01*
X-27090Y93821D01*
X-27924Y95280D01*
X-28340Y96947D01*
X-27924Y98613D01*
X-27090Y100072D01*
X-25840Y100905D01*
X-24590Y101113D01*
X-23340Y100905D01*
X-22090Y100072D01*
X-21257Y98613D01*
X-21048Y96947D01*
X-21257Y95280D01*
X-22090Y93821D01*
X-23340Y92988D01*
X-24590Y92780D01*
G01X-9090D02*
Y105280D01*
G01X6410Y92780D02*
Y105280D01*
G01X21910Y92780D02*
X20660Y92988D01*
X19410Y93821D01*
X18576Y95280D01*
X18160Y96947D01*
X18576Y98613D01*
X19410Y100072D01*
X20660Y100905D01*
X21910Y101113D01*
X23160Y100905D01*
X24410Y100072D01*
X25243Y98613D01*
X25452Y96947D01*
X25243Y95280D01*
X24410Y93821D01*
X23160Y92988D01*
X21910Y92780D01*
G01X32201Y101113D02*
X34702Y92780D01*
X37410Y101113D01*
X40118Y92780D01*
X42619Y101113D01*
G01X65493Y89655D02*
X66952Y88822D01*
X68618Y88613D01*
X70077Y88822D01*
X71327Y89863D01*
X72160Y91322D01*
Y101113D01*
G01Y99447D02*
X71327Y100280D01*
X70077Y100905D01*
X68618Y101113D01*
X66952Y100697D01*
X65910Y99863D01*
X65076Y98405D01*
X64660Y96947D01*
X64868Y95696D01*
X65702Y94238D01*
X66952Y93197D01*
X68618Y92780D01*
X69868Y92988D01*
X71327Y93821D01*
X72160Y94655D01*
G01X80785Y98405D02*
X87452D01*
X86827Y99863D01*
X85785Y100697D01*
X84327Y101113D01*
X82868Y100905D01*
X81618Y100280D01*
X80785Y98822D01*
X80368Y97571D01*
Y96322D01*
X80785Y95072D01*
X81827Y93821D01*
X83077Y92988D01*
X84535Y92780D01*
X85993Y93197D01*
X87452Y94446D01*
G01X96493Y92780D02*
Y101113D01*
G01Y99447D02*
X97535Y100280D01*
X98577Y100905D01*
X100035Y101113D01*
X101077Y100905D01*
X102327Y100280D01*
G01X111160Y92780D02*
Y105280D01*
G01Y99030D02*
X112202Y100280D01*
X113452Y100905D01*
X114702Y101113D01*
X116577Y100697D01*
X117827Y99863D01*
X118660Y98405D01*
Y96738D01*
X118243Y95072D01*
X117410Y93821D01*
X115952Y92988D01*
X114702Y92780D01*
X113452Y92988D01*
X112202Y93613D01*
X111160Y94655D01*
G01X127285Y98405D02*
X133952D01*
X133327Y99863D01*
X132285Y100697D01*
X130827Y101113D01*
X129368Y100905D01*
X128118Y100280D01*
X127285Y98822D01*
X126868Y97571D01*
Y96322D01*
X127285Y95072D01*
X128327Y93821D01*
X129577Y92988D01*
X131035Y92780D01*
X132493Y93197D01*
X133952Y94446D01*
G01X142993Y92780D02*
Y101113D01*
G01Y99447D02*
X144035Y100280D01*
X145077Y100905D01*
X146535Y101113D01*
X147577Y100905D01*
X148827Y100280D01*
G01X180660Y105280D02*
Y92780D01*
G01Y94655D02*
X179827Y93613D01*
X178577Y92988D01*
X177118Y92780D01*
X175452Y93197D01*
X174202Y94238D01*
X173368Y95488D01*
X173160Y96947D01*
X173368Y98405D01*
X174202Y99655D01*
X175452Y100697D01*
X177118Y101113D01*
X178577Y100905D01*
X179618Y100488D01*
X180660Y99655D01*
G01X189285Y98405D02*
X195952D01*
X195327Y99863D01*
X194285Y100697D01*
X192827Y101113D01*
X191368Y100905D01*
X190118Y100280D01*
X189285Y98822D01*
X188868Y97571D01*
Y96322D01*
X189285Y95072D01*
X190327Y93821D01*
X191577Y92988D01*
X193035Y92780D01*
X194493Y93197D01*
X195952Y94446D01*
G01X204785Y94238D02*
X205827Y93405D01*
X207285Y92780D01*
X208535D01*
X209785Y93197D01*
X210618Y93821D01*
X211035Y94655D01*
X210827Y95905D01*
X209993Y96530D01*
X206243Y97780D01*
X205410Y99238D01*
X205827Y100280D01*
X206660Y100905D01*
X207910Y101113D01*
X209160Y100905D01*
X210410Y100280D01*
G01X223410Y101113D02*
Y92780D01*
G01Y104446D02*
X222993Y104655D01*
Y105072D01*
X223410Y105280D01*
X223827Y105072D01*
Y104655D01*
X223410Y104446D01*
G01X235993Y89655D02*
X237452Y88822D01*
X239118Y88613D01*
X240577Y88822D01*
X241827Y89863D01*
X242660Y91322D01*
Y101113D01*
G01Y99447D02*
X241827Y100280D01*
X240577Y100905D01*
X239118Y101113D01*
X237452Y100697D01*
X236410Y99863D01*
X235576Y98405D01*
X235160Y96947D01*
X235368Y95696D01*
X236202Y94238D01*
X237452Y93197D01*
X239118Y92780D01*
X240368Y92988D01*
X241827Y93821D01*
X242660Y94655D01*
G01X250868Y92780D02*
Y101113D01*
G01Y99030D02*
X251702Y100072D01*
X252952Y100905D01*
X254618Y101113D01*
X256077Y100905D01*
X257327Y100072D01*
X257952Y98613D01*
Y92780D01*
G01X-44048Y114480D02*
Y126980D01*
X-36132D01*
G01X-39048Y120938D02*
X-44048D01*
G01X-24590Y114480D02*
X-25840Y114688D01*
X-27090Y115521D01*
X-27924Y116980D01*
X-28340Y118647D01*
X-27924Y120313D01*
X-27090Y121772D01*
X-25840Y122605D01*
X-24590Y122813D01*
X-23340Y122605D01*
X-22090Y121772D01*
X-21257Y120313D01*
X-21048Y118647D01*
X-21257Y116980D01*
X-22090Y115521D01*
X-23340Y114688D01*
X-24590Y114480D01*
G01X-12007D02*
Y122813D01*
G01Y121147D02*
X-10965Y121980D01*
X-9923Y122605D01*
X-8465Y122813D01*
X-7423Y122605D01*
X-6173Y121980D01*
G01X17952Y124897D02*
X19202Y126146D01*
X20660Y126772D01*
X22327Y126980D01*
X24410Y126563D01*
X25868Y125522D01*
X26285Y124272D01*
X26077Y123021D01*
X25243Y121980D01*
X21077Y119897D01*
X19202Y118438D01*
X17952Y116355D01*
X17535Y114480D01*
X26285D01*
G01X36993D02*
X37410Y117188D01*
X38035Y119480D01*
X38868Y121563D01*
X39910Y123855D01*
X41577Y126980D01*
X33243D01*
G01X55410Y114480D02*
Y126980D01*
X47701Y118022D01*
X58119D01*
G01X64035Y114480D02*
X72785Y126980D01*
G01X64035D02*
X72785Y114480D01*
G01X96493Y111355D02*
X97952Y110522D01*
X99618Y110313D01*
X101077Y110522D01*
X102327Y111563D01*
X103160Y113022D01*
Y122813D01*
G01Y121147D02*
X102327Y121980D01*
X101077Y122605D01*
X99618Y122813D01*
X97952Y122397D01*
X96910Y121563D01*
X96076Y120105D01*
X95660Y118647D01*
X95868Y117396D01*
X96702Y115938D01*
X97952Y114897D01*
X99618Y114480D01*
X100868Y114688D01*
X102327Y115521D01*
X103160Y116355D01*
G01X111785Y120105D02*
X118452D01*
X117827Y121563D01*
X116785Y122397D01*
X115327Y122813D01*
X113868Y122605D01*
X112618Y121980D01*
X111785Y120522D01*
X111368Y119271D01*
Y118022D01*
X111785Y116772D01*
X112827Y115521D01*
X114077Y114688D01*
X115535Y114480D01*
X116993Y114897D01*
X118452Y116146D01*
G01X127493Y114480D02*
Y122813D01*
G01Y121147D02*
X128535Y121980D01*
X129577Y122605D01*
X131035Y122813D01*
X132077Y122605D01*
X133327Y121980D01*
G01X142160Y114480D02*
Y126980D01*
G01Y120730D02*
X143202Y121980D01*
X144452Y122605D01*
X145702Y122813D01*
X147577Y122397D01*
X148827Y121563D01*
X149660Y120105D01*
Y118438D01*
X149243Y116772D01*
X148410Y115521D01*
X146952Y114688D01*
X145702Y114480D01*
X144452Y114688D01*
X143202Y115313D01*
X142160Y116355D01*
G01X158285Y120105D02*
X164952D01*
X164327Y121563D01*
X163285Y122397D01*
X161827Y122813D01*
X160368Y122605D01*
X159118Y121980D01*
X158285Y120522D01*
X157868Y119271D01*
Y118022D01*
X158285Y116772D01*
X159327Y115521D01*
X160577Y114688D01*
X162035Y114480D01*
X163493Y114897D01*
X164952Y116146D01*
G01X173993Y114480D02*
Y122813D01*
G01Y121147D02*
X175035Y121980D01*
X176077Y122605D01*
X177535Y122813D01*
X178577Y122605D01*
X179827Y121980D01*
G01X206660Y114480D02*
Y125105D01*
X207077Y126146D01*
X207910Y126772D01*
X209160Y126980D01*
X210410Y126563D01*
X211035Y125522D01*
G01X208535Y121980D02*
X204368D01*
G01X223410Y114480D02*
X222160Y114688D01*
X220910Y115521D01*
X220076Y116980D01*
X219660Y118647D01*
X220076Y120313D01*
X220910Y121772D01*
X222160Y122605D01*
X223410Y122813D01*
X224660Y122605D01*
X225910Y121772D01*
X226743Y120313D01*
X226952Y118647D01*
X226743Y116980D01*
X225910Y115521D01*
X224660Y114688D01*
X223410Y114480D01*
G01X235993D02*
Y122813D01*
G01Y121147D02*
X237035Y121980D01*
X238077Y122605D01*
X239535Y122813D01*
X240577Y122605D01*
X241827Y121980D01*
G01X248160Y114480D02*
Y122813D01*
G01Y120522D02*
X248785Y121563D01*
X249827Y122397D01*
X251285Y122813D01*
X252743Y122397D01*
X253785Y121563D01*
X254410Y120522D01*
Y114480D01*
G01Y120522D02*
X255035Y121563D01*
X256077Y122397D01*
X257535Y122813D01*
X258993Y122397D01*
X260035Y121563D01*
X260660Y120313D01*
Y114480D01*
G01X273660D02*
Y122813D01*
G01Y121355D02*
X272827Y122188D01*
X271577Y122605D01*
X270118Y122813D01*
X268660Y122397D01*
X267410Y121563D01*
X266576Y120313D01*
X266160Y118647D01*
X266576Y116980D01*
X267410Y115730D01*
X268660Y114897D01*
X270118Y114480D01*
X271577Y114688D01*
X272827Y115313D01*
X273660Y116146D01*
G01X285410Y126980D02*
Y114480D01*
G01X282493Y122813D02*
X288327D01*
G01X316410Y126980D02*
Y114480D01*
G01X313493Y122813D02*
X319327D01*
G01X328368Y114480D02*
Y126980D01*
G01Y120938D02*
X329410Y121980D01*
X330452Y122605D01*
X332118Y122813D01*
X333368Y122605D01*
X334827Y121772D01*
X335452Y120522D01*
Y114480D01*
G01X344285Y120105D02*
X350952D01*
X350327Y121563D01*
X349285Y122397D01*
X347827Y122813D01*
X346368Y122605D01*
X345118Y121980D01*
X344285Y120522D01*
X343868Y119271D01*
Y118022D01*
X344285Y116772D01*
X345327Y115521D01*
X346577Y114688D01*
X348035Y114480D01*
X349493Y114897D01*
X350952Y116146D01*
G01X359993Y114480D02*
Y122813D01*
G01Y121147D02*
X361035Y121980D01*
X362077Y122605D01*
X363535Y122813D01*
X364577Y122605D01*
X365827Y121980D01*
G01X372160Y114480D02*
Y122813D01*
G01Y120522D02*
X372785Y121563D01*
X373827Y122397D01*
X375285Y122813D01*
X376743Y122397D01*
X377785Y121563D01*
X378410Y120522D01*
Y114480D01*
G01Y120522D02*
X379035Y121563D01*
X380077Y122397D01*
X381535Y122813D01*
X382993Y122397D01*
X384035Y121563D01*
X384660Y120313D01*
Y114480D01*
G01X397660D02*
Y122813D01*
G01Y121355D02*
X396827Y122188D01*
X395577Y122605D01*
X394118Y122813D01*
X392660Y122397D01*
X391410Y121563D01*
X390576Y120313D01*
X390160Y118647D01*
X390576Y116980D01*
X391410Y115730D01*
X392660Y114897D01*
X394118Y114480D01*
X395577Y114688D01*
X396827Y115313D01*
X397660Y116146D01*
G01X409410Y114480D02*
Y126980D01*
G01X437493Y114480D02*
Y122813D01*
G01Y121147D02*
X438535Y121980D01*
X439577Y122605D01*
X441035Y122813D01*
X442077Y122605D01*
X443327Y121980D01*
G01X452785Y120105D02*
X459452D01*
X458827Y121563D01*
X457785Y122397D01*
X456327Y122813D01*
X454868Y122605D01*
X453618Y121980D01*
X452785Y120522D01*
X452368Y119271D01*
Y118022D01*
X452785Y116772D01*
X453827Y115521D01*
X455077Y114688D01*
X456535Y114480D01*
X457993Y114897D01*
X459452Y116146D01*
G01X471410Y114480D02*
Y126980D01*
G01X486910Y122813D02*
Y114480D01*
G01Y126146D02*
X486493Y126355D01*
Y126772D01*
X486910Y126980D01*
X487327Y126772D01*
Y126355D01*
X486910Y126146D01*
G01X499285Y120105D02*
X505952D01*
X505327Y121563D01*
X504285Y122397D01*
X502827Y122813D01*
X501368Y122605D01*
X500118Y121980D01*
X499285Y120522D01*
X498868Y119271D01*
Y118022D01*
X499285Y116772D01*
X500327Y115521D01*
X501577Y114688D01*
X503035Y114480D01*
X504493Y114897D01*
X505952Y116146D01*
G01X516660Y114480D02*
Y125105D01*
X517077Y126146D01*
X517910Y126772D01*
X519160Y126980D01*
X520410Y126563D01*
X521035Y125522D01*
G01X518535Y121980D02*
X514368D01*
G01X-31740Y546680D02*
Y557305D01*
X-31323Y558346D01*
X-30490Y558972D01*
X-29240Y559180D01*
X-27990Y558763D01*
X-27365Y557722D01*
G01X-29865Y554180D02*
X-34032D01*
G01X-14990Y546680D02*
X-16240Y546888D01*
X-17490Y547721D01*
X-18324Y549180D01*
X-18740Y550847D01*
X-18324Y552513D01*
X-17490Y553972D01*
X-16240Y554805D01*
X-14990Y555013D01*
X-13740Y554805D01*
X-12490Y553972D01*
X-11657Y552513D01*
X-11448Y550847D01*
X-11657Y549180D01*
X-12490Y547721D01*
X-13740Y546888D01*
X-14990Y546680D01*
G01X510D02*
Y559180D01*
G01X16010Y546680D02*
Y559180D01*
G01X31510Y546680D02*
X30260Y546888D01*
X29010Y547721D01*
X28176Y549180D01*
X27760Y550847D01*
X28176Y552513D01*
X29010Y553972D01*
X30260Y554805D01*
X31510Y555013D01*
X32760Y554805D01*
X34010Y553972D01*
X34843Y552513D01*
X35052Y550847D01*
X34843Y549180D01*
X34010Y547721D01*
X32760Y546888D01*
X31510Y546680D01*
G01X41801Y555013D02*
X44302Y546680D01*
X47010Y555013D01*
X49718Y546680D01*
X52219Y555013D01*
G01X75093Y543555D02*
X76552Y542722D01*
X78218Y542513D01*
X79677Y542722D01*
X80927Y543763D01*
X81760Y545222D01*
Y555013D01*
G01Y553347D02*
X80927Y554180D01*
X79677Y554805D01*
X78218Y555013D01*
X76552Y554597D01*
X75510Y553763D01*
X74676Y552305D01*
X74260Y550847D01*
X74468Y549596D01*
X75302Y548138D01*
X76552Y547097D01*
X78218Y546680D01*
X79468Y546888D01*
X80927Y547721D01*
X81760Y548555D01*
G01X90385Y552305D02*
X97052D01*
X96427Y553763D01*
X95385Y554597D01*
X93927Y555013D01*
X92468Y554805D01*
X91218Y554180D01*
X90385Y552722D01*
X89968Y551471D01*
Y550222D01*
X90385Y548972D01*
X91427Y547721D01*
X92677Y546888D01*
X94135Y546680D01*
X95593Y547097D01*
X97052Y548346D01*
G01X106093Y546680D02*
Y555013D01*
G01Y553347D02*
X107135Y554180D01*
X108177Y554805D01*
X109635Y555013D01*
X110677Y554805D01*
X111927Y554180D01*
G01X120760Y546680D02*
Y559180D01*
G01Y552930D02*
X121802Y554180D01*
X123052Y554805D01*
X124302Y555013D01*
X126177Y554597D01*
X127427Y553763D01*
X128260Y552305D01*
Y550638D01*
X127843Y548972D01*
X127010Y547721D01*
X125552Y546888D01*
X124302Y546680D01*
X123052Y546888D01*
X121802Y547513D01*
X120760Y548555D01*
G01X136885Y552305D02*
X143552D01*
X142927Y553763D01*
X141885Y554597D01*
X140427Y555013D01*
X138968Y554805D01*
X137718Y554180D01*
X136885Y552722D01*
X136468Y551471D01*
Y550222D01*
X136885Y548972D01*
X137927Y547721D01*
X139177Y546888D01*
X140635Y546680D01*
X142093Y547097D01*
X143552Y548346D01*
G01X152593Y546680D02*
Y555013D01*
G01Y553347D02*
X153635Y554180D01*
X154677Y554805D01*
X156135Y555013D01*
X157177Y554805D01*
X158427Y554180D01*
G01X190260Y559180D02*
Y546680D01*
G01Y548555D02*
X189427Y547513D01*
X188177Y546888D01*
X186718Y546680D01*
X185052Y547097D01*
X183802Y548138D01*
X182968Y549388D01*
X182760Y550847D01*
X182968Y552305D01*
X183802Y553555D01*
X185052Y554597D01*
X186718Y555013D01*
X188177Y554805D01*
X189218Y554388D01*
X190260Y553555D01*
G01X198885Y552305D02*
X205552D01*
X204927Y553763D01*
X203885Y554597D01*
X202427Y555013D01*
X200968Y554805D01*
X199718Y554180D01*
X198885Y552722D01*
X198468Y551471D01*
Y550222D01*
X198885Y548972D01*
X199927Y547721D01*
X201177Y546888D01*
X202635Y546680D01*
X204093Y547097D01*
X205552Y548346D01*
G01X214385Y548138D02*
X215427Y547305D01*
X216885Y546680D01*
X218135D01*
X219385Y547097D01*
X220218Y547721D01*
X220635Y548555D01*
X220427Y549805D01*
X219593Y550430D01*
X215843Y551680D01*
X215010Y553138D01*
X215427Y554180D01*
X216260Y554805D01*
X217510Y555013D01*
X218760Y554805D01*
X220010Y554180D01*
G01X233010Y555013D02*
Y546680D01*
G01Y558346D02*
X232593Y558555D01*
Y558972D01*
X233010Y559180D01*
X233427Y558972D01*
Y558555D01*
X233010Y558346D01*
G01X245593Y543555D02*
X247052Y542722D01*
X248718Y542513D01*
X250177Y542722D01*
X251427Y543763D01*
X252260Y545222D01*
Y555013D01*
G01Y553347D02*
X251427Y554180D01*
X250177Y554805D01*
X248718Y555013D01*
X247052Y554597D01*
X246010Y553763D01*
X245176Y552305D01*
X244760Y550847D01*
X244968Y549596D01*
X245802Y548138D01*
X247052Y547097D01*
X248718Y546680D01*
X249968Y546888D01*
X251427Y547721D01*
X252260Y548555D01*
G01X260468Y546680D02*
Y555013D01*
G01Y552930D02*
X261302Y553972D01*
X262552Y554805D01*
X264218Y555013D01*
X265677Y554805D01*
X266927Y553972D01*
X267552Y552513D01*
Y546680D01*
G01X-34448Y568380D02*
Y580880D01*
X-26532D01*
G01X-29448Y574838D02*
X-34448D01*
G01X-14990Y568380D02*
X-16240Y568588D01*
X-17490Y569421D01*
X-18324Y570880D01*
X-18740Y572547D01*
X-18324Y574213D01*
X-17490Y575672D01*
X-16240Y576505D01*
X-14990Y576713D01*
X-13740Y576505D01*
X-12490Y575672D01*
X-11657Y574213D01*
X-11448Y572547D01*
X-11657Y570880D01*
X-12490Y569421D01*
X-13740Y568588D01*
X-14990Y568380D01*
G01X-2407D02*
Y576713D01*
G01Y575047D02*
X-1365Y575880D01*
X-323Y576505D01*
X1135Y576713D01*
X2177Y576505D01*
X3427Y575880D01*
G01X27552Y578797D02*
X28802Y580046D01*
X30260Y580672D01*
X31927Y580880D01*
X34010Y580463D01*
X35468Y579422D01*
X35885Y578172D01*
X35677Y576921D01*
X34843Y575880D01*
X30677Y573797D01*
X28802Y572338D01*
X27552Y570255D01*
X27135Y568380D01*
X35885D01*
G01X46593D02*
X47010Y571088D01*
X47635Y573380D01*
X48468Y575463D01*
X49510Y577755D01*
X51177Y580880D01*
X42843D01*
G01X65010Y568380D02*
Y580880D01*
X57301Y571922D01*
X67719D01*
G01X73635Y568380D02*
X82385Y580880D01*
G01X73635D02*
X82385Y568380D01*
G01X106093Y565255D02*
X107552Y564422D01*
X109218Y564213D01*
X110677Y564422D01*
X111927Y565463D01*
X112760Y566922D01*
Y576713D01*
G01Y575047D02*
X111927Y575880D01*
X110677Y576505D01*
X109218Y576713D01*
X107552Y576297D01*
X106510Y575463D01*
X105676Y574005D01*
X105260Y572547D01*
X105468Y571296D01*
X106302Y569838D01*
X107552Y568797D01*
X109218Y568380D01*
X110468Y568588D01*
X111927Y569421D01*
X112760Y570255D01*
G01X121385Y574005D02*
X128052D01*
X127427Y575463D01*
X126385Y576297D01*
X124927Y576713D01*
X123468Y576505D01*
X122218Y575880D01*
X121385Y574422D01*
X120968Y573171D01*
Y571922D01*
X121385Y570672D01*
X122427Y569421D01*
X123677Y568588D01*
X125135Y568380D01*
X126593Y568797D01*
X128052Y570046D01*
G01X137093Y568380D02*
Y576713D01*
G01Y575047D02*
X138135Y575880D01*
X139177Y576505D01*
X140635Y576713D01*
X141677Y576505D01*
X142927Y575880D01*
G01X151760Y568380D02*
Y580880D01*
G01Y574630D02*
X152802Y575880D01*
X154052Y576505D01*
X155302Y576713D01*
X157177Y576297D01*
X158427Y575463D01*
X159260Y574005D01*
Y572338D01*
X158843Y570672D01*
X158010Y569421D01*
X156552Y568588D01*
X155302Y568380D01*
X154052Y568588D01*
X152802Y569213D01*
X151760Y570255D01*
G01X167885Y574005D02*
X174552D01*
X173927Y575463D01*
X172885Y576297D01*
X171427Y576713D01*
X169968Y576505D01*
X168718Y575880D01*
X167885Y574422D01*
X167468Y573171D01*
Y571922D01*
X167885Y570672D01*
X168927Y569421D01*
X170177Y568588D01*
X171635Y568380D01*
X173093Y568797D01*
X174552Y570046D01*
G01X183593Y568380D02*
Y576713D01*
G01Y575047D02*
X184635Y575880D01*
X185677Y576505D01*
X187135Y576713D01*
X188177Y576505D01*
X189427Y575880D01*
G01X216260Y568380D02*
Y579005D01*
X216677Y580046D01*
X217510Y580672D01*
X218760Y580880D01*
X220010Y580463D01*
X220635Y579422D01*
G01X218135Y575880D02*
X213968D01*
G01X233010Y568380D02*
X231760Y568588D01*
X230510Y569421D01*
X229676Y570880D01*
X229260Y572547D01*
X229676Y574213D01*
X230510Y575672D01*
X231760Y576505D01*
X233010Y576713D01*
X234260Y576505D01*
X235510Y575672D01*
X236343Y574213D01*
X236552Y572547D01*
X236343Y570880D01*
X235510Y569421D01*
X234260Y568588D01*
X233010Y568380D01*
G01X245593D02*
Y576713D01*
G01Y575047D02*
X246635Y575880D01*
X247677Y576505D01*
X249135Y576713D01*
X250177Y576505D01*
X251427Y575880D01*
G01X257760Y568380D02*
Y576713D01*
G01Y574422D02*
X258385Y575463D01*
X259427Y576297D01*
X260885Y576713D01*
X262343Y576297D01*
X263385Y575463D01*
X264010Y574422D01*
Y568380D01*
G01Y574422D02*
X264635Y575463D01*
X265677Y576297D01*
X267135Y576713D01*
X268593Y576297D01*
X269635Y575463D01*
X270260Y574213D01*
Y568380D01*
G01X283260D02*
Y576713D01*
G01Y575255D02*
X282427Y576088D01*
X281177Y576505D01*
X279718Y576713D01*
X278260Y576297D01*
X277010Y575463D01*
X276176Y574213D01*
X275760Y572547D01*
X276176Y570880D01*
X277010Y569630D01*
X278260Y568797D01*
X279718Y568380D01*
X281177Y568588D01*
X282427Y569213D01*
X283260Y570046D01*
G01X295010Y580880D02*
Y568380D01*
G01X292093Y576713D02*
X297927D01*
G01X326010Y580880D02*
Y568380D01*
G01X323093Y576713D02*
X328927D01*
G01X337968Y568380D02*
Y580880D01*
G01Y574838D02*
X339010Y575880D01*
X340052Y576505D01*
X341718Y576713D01*
X342968Y576505D01*
X344427Y575672D01*
X345052Y574422D01*
Y568380D01*
G01X353885Y574005D02*
X360552D01*
X359927Y575463D01*
X358885Y576297D01*
X357427Y576713D01*
X355968Y576505D01*
X354718Y575880D01*
X353885Y574422D01*
X353468Y573171D01*
Y571922D01*
X353885Y570672D01*
X354927Y569421D01*
X356177Y568588D01*
X357635Y568380D01*
X359093Y568797D01*
X360552Y570046D01*
G01X369593Y568380D02*
Y576713D01*
G01Y575047D02*
X370635Y575880D01*
X371677Y576505D01*
X373135Y576713D01*
X374177Y576505D01*
X375427Y575880D01*
G01X381760Y568380D02*
Y576713D01*
G01Y574422D02*
X382385Y575463D01*
X383427Y576297D01*
X384885Y576713D01*
X386343Y576297D01*
X387385Y575463D01*
X388010Y574422D01*
Y568380D01*
G01Y574422D02*
X388635Y575463D01*
X389677Y576297D01*
X391135Y576713D01*
X392593Y576297D01*
X393635Y575463D01*
X394260Y574213D01*
Y568380D01*
G01X407260D02*
Y576713D01*
G01Y575255D02*
X406427Y576088D01*
X405177Y576505D01*
X403718Y576713D01*
X402260Y576297D01*
X401010Y575463D01*
X400176Y574213D01*
X399760Y572547D01*
X400176Y570880D01*
X401010Y569630D01*
X402260Y568797D01*
X403718Y568380D01*
X405177Y568588D01*
X406427Y569213D01*
X407260Y570046D01*
G01X419010Y568380D02*
Y580880D01*
G01X447093Y568380D02*
Y576713D01*
G01Y575047D02*
X448135Y575880D01*
X449177Y576505D01*
X450635Y576713D01*
X451677Y576505D01*
X452927Y575880D01*
G01X462385Y574005D02*
X469052D01*
X468427Y575463D01*
X467385Y576297D01*
X465927Y576713D01*
X464468Y576505D01*
X463218Y575880D01*
X462385Y574422D01*
X461968Y573171D01*
Y571922D01*
X462385Y570672D01*
X463427Y569421D01*
X464677Y568588D01*
X466135Y568380D01*
X467593Y568797D01*
X469052Y570046D01*
G01X481010Y568380D02*
Y580880D01*
G01X496510Y576713D02*
Y568380D01*
G01Y580046D02*
X496093Y580255D01*
Y580672D01*
X496510Y580880D01*
X496927Y580672D01*
Y580255D01*
X496510Y580046D01*
G01X508885Y574005D02*
X515552D01*
X514927Y575463D01*
X513885Y576297D01*
X512427Y576713D01*
X510968Y576505D01*
X509718Y575880D01*
X508885Y574422D01*
X508468Y573171D01*
Y571922D01*
X508885Y570672D01*
X509927Y569421D01*
X511177Y568588D01*
X512635Y568380D01*
X514093Y568797D01*
X515552Y570046D01*
G01X526260Y568380D02*
Y579005D01*
X526677Y580046D01*
X527510Y580672D01*
X528760Y580880D01*
X530010Y580463D01*
X530635Y579422D01*
G01X528135Y575880D02*
X523968D01*
G01X35427Y868280D02*
Y880780D01*
X39593D01*
X41260Y880155D01*
X42510Y879322D01*
X43552Y878072D01*
X44385Y876613D01*
X44593Y874530D01*
X44385Y872447D01*
X43552Y870988D01*
X42510Y869738D01*
X41260Y868905D01*
X39593Y868280D01*
X35427D01*
G01X52385Y873905D02*
X59052D01*
X58427Y875363D01*
X57385Y876197D01*
X55927Y876613D01*
X54468Y876405D01*
X53218Y875780D01*
X52385Y874322D01*
X51968Y873071D01*
Y871822D01*
X52385Y870572D01*
X53427Y869321D01*
X54677Y868488D01*
X56135Y868280D01*
X57593Y868697D01*
X59052Y869946D01*
G01X69760Y868280D02*
Y878905D01*
X70177Y879946D01*
X71010Y880572D01*
X72260Y880780D01*
X73510Y880363D01*
X74135Y879322D01*
G01X71635Y875780D02*
X67468D01*
G01X86510Y876613D02*
Y868280D01*
G01Y879946D02*
X86093Y880155D01*
Y880572D01*
X86510Y880780D01*
X86927Y880572D01*
Y880155D01*
X86510Y879946D01*
G01X98468Y868280D02*
Y876613D01*
G01Y874530D02*
X99302Y875572D01*
X100552Y876405D01*
X102218Y876613D01*
X103677Y876405D01*
X104927Y875572D01*
X105552Y874113D01*
Y868280D01*
G01X114385Y873905D02*
X121052D01*
X120427Y875363D01*
X119385Y876197D01*
X117927Y876613D01*
X116468Y876405D01*
X115218Y875780D01*
X114385Y874322D01*
X113968Y873071D01*
Y871822D01*
X114385Y870572D01*
X115427Y869321D01*
X116677Y868488D01*
X118135Y868280D01*
X119593Y868697D01*
X121052Y869946D01*
G01X148510Y880780D02*
Y868280D01*
G01X145593Y876613D02*
X151427D01*
G01X160468Y868280D02*
Y880780D01*
G01Y874738D02*
X161510Y875780D01*
X162552Y876405D01*
X164218Y876613D01*
X165468Y876405D01*
X166927Y875572D01*
X167552Y874322D01*
Y868280D01*
G01X176385Y873905D02*
X183052D01*
X182427Y875363D01*
X181385Y876197D01*
X179927Y876613D01*
X178468Y876405D01*
X177218Y875780D01*
X176385Y874322D01*
X175968Y873071D01*
Y871822D01*
X176385Y870572D01*
X177427Y869321D01*
X178677Y868488D01*
X180135Y868280D01*
X181593Y868697D01*
X183052Y869946D01*
G01X192093Y868280D02*
Y876613D01*
G01Y874947D02*
X193135Y875780D01*
X194177Y876405D01*
X195635Y876613D01*
X196677Y876405D01*
X197927Y875780D01*
G01X204260Y868280D02*
Y876613D01*
G01Y874322D02*
X204885Y875363D01*
X205927Y876197D01*
X207385Y876613D01*
X208843Y876197D01*
X209885Y875363D01*
X210510Y874322D01*
Y868280D01*
G01Y874322D02*
X211135Y875363D01*
X212177Y876197D01*
X213635Y876613D01*
X215093Y876197D01*
X216135Y875363D01*
X216760Y874113D01*
Y868280D01*
G01X229760D02*
Y876613D01*
G01Y875155D02*
X228927Y875988D01*
X227677Y876405D01*
X226218Y876613D01*
X224760Y876197D01*
X223510Y875363D01*
X222676Y874113D01*
X222260Y872447D01*
X222676Y870780D01*
X223510Y869530D01*
X224760Y868697D01*
X226218Y868280D01*
X227677Y868488D01*
X228927Y869113D01*
X229760Y869946D01*
G01X241510Y868280D02*
Y880780D01*
G01X269593Y868280D02*
Y876613D01*
G01Y874947D02*
X270635Y875780D01*
X271677Y876405D01*
X273135Y876613D01*
X274177Y876405D01*
X275427Y875780D01*
G01X284885Y873905D02*
X291552D01*
X290927Y875363D01*
X289885Y876197D01*
X288427Y876613D01*
X286968Y876405D01*
X285718Y875780D01*
X284885Y874322D01*
X284468Y873071D01*
Y871822D01*
X284885Y870572D01*
X285927Y869321D01*
X287177Y868488D01*
X288635Y868280D01*
X290093Y868697D01*
X291552Y869946D01*
G01X303510Y868280D02*
Y880780D01*
G01X319010Y876613D02*
Y868280D01*
G01Y879946D02*
X318593Y880155D01*
Y880572D01*
X319010Y880780D01*
X319427Y880572D01*
Y880155D01*
X319010Y879946D01*
G01X331385Y873905D02*
X338052D01*
X337427Y875363D01*
X336385Y876197D01*
X334927Y876613D01*
X333468Y876405D01*
X332218Y875780D01*
X331385Y874322D01*
X330968Y873071D01*
Y871822D01*
X331385Y870572D01*
X332427Y869321D01*
X333677Y868488D01*
X335135Y868280D01*
X336593Y868697D01*
X338052Y869946D01*
G01X348760Y868280D02*
Y878905D01*
X349177Y879946D01*
X350010Y880572D01*
X351260Y880780D01*
X352510Y880363D01*
X353135Y879322D01*
G01X350635Y875780D02*
X346468D01*
G01X384343Y875572D02*
X382885Y876405D01*
X381635Y876613D01*
X379968Y876197D01*
X378718Y875363D01*
X377885Y873905D01*
X377676Y872447D01*
X377885Y870988D01*
X378718Y869738D01*
X379968Y868697D01*
X381635Y868280D01*
X383093Y868697D01*
X384343Y869530D01*
G01X396510Y868280D02*
X395260Y868488D01*
X394010Y869321D01*
X393176Y870780D01*
X392760Y872447D01*
X393176Y874113D01*
X394010Y875572D01*
X395260Y876405D01*
X396510Y876613D01*
X397760Y876405D01*
X399010Y875572D01*
X399843Y874113D01*
X400052Y872447D01*
X399843Y870780D01*
X399010Y869321D01*
X397760Y868488D01*
X396510Y868280D01*
G01X408468D02*
Y876613D01*
G01Y874530D02*
X409302Y875572D01*
X410552Y876405D01*
X412218Y876613D01*
X413677Y876405D01*
X414927Y875572D01*
X415552Y874113D01*
Y868280D01*
G01X423968D02*
Y876613D01*
G01Y874530D02*
X424802Y875572D01*
X426052Y876405D01*
X427718Y876613D01*
X429177Y876405D01*
X430427Y875572D01*
X431052Y874113D01*
Y868280D01*
G01X439885Y873905D02*
X446552D01*
X445927Y875363D01*
X444885Y876197D01*
X443427Y876613D01*
X441968Y876405D01*
X440718Y875780D01*
X439885Y874322D01*
X439468Y873071D01*
Y871822D01*
X439885Y870572D01*
X440927Y869321D01*
X442177Y868488D01*
X443635Y868280D01*
X445093Y868697D01*
X446552Y869946D01*
G01X461843Y875572D02*
X460385Y876405D01*
X459135Y876613D01*
X457468Y876197D01*
X456218Y875363D01*
X455385Y873905D01*
X455176Y872447D01*
X455385Y870988D01*
X456218Y869738D01*
X457468Y868697D01*
X459135Y868280D01*
X460593Y868697D01*
X461843Y869530D01*
G01X474010Y880780D02*
Y868280D01*
G01X471093Y876613D02*
X476927D01*
G01X707527Y439663D02*
X716693Y448830D01*
G01X712110Y450497D02*
Y437997D01*
G01X716693Y439663D02*
X707527Y448830D01*
G01X705860Y444247D02*
X718360D01*
G01X723027Y439663D02*
X732193Y448830D01*
G01X727610Y450497D02*
Y437997D01*
G01X732193Y439663D02*
X723027Y448830D01*
G01X721360Y444247D02*
X733860D01*
G01X738527Y439663D02*
X747693Y448830D01*
G01X743110Y450497D02*
Y437997D01*
G01X747693Y439663D02*
X738527Y448830D01*
G01X736860Y444247D02*
X749360D01*
G01X754027Y439663D02*
X763193Y448830D01*
G01X758610Y450497D02*
Y437997D01*
G01X763193Y439663D02*
X754027Y448830D01*
G01X752360Y444247D02*
X764860D01*
G01X774110Y439663D02*
X773693Y439872D01*
Y440288D01*
X774110Y440497D01*
X774527Y440288D01*
Y439872D01*
X774110Y439663D01*
G01Y445288D02*
X773693Y445497D01*
Y445913D01*
X774110Y446122D01*
X774527Y445913D01*
Y445497D01*
X774110Y445288D01*
G01X802610Y452580D02*
X807610D01*
G01X805110D02*
Y440080D01*
G01X802610D02*
X807610D01*
G01X817693Y436955D02*
X819152Y436122D01*
X820818Y435913D01*
X822277Y436122D01*
X823527Y437163D01*
X824360Y438622D01*
Y448413D01*
G01Y446747D02*
X823527Y447580D01*
X822277Y448205D01*
X820818Y448413D01*
X819152Y447997D01*
X818110Y447163D01*
X817276Y445705D01*
X816860Y444247D01*
X817068Y442996D01*
X817902Y441538D01*
X819152Y440497D01*
X820818Y440080D01*
X822068Y440288D01*
X823527Y441121D01*
X824360Y441955D01*
G01X832568Y440080D02*
Y448413D01*
G01Y446330D02*
X833402Y447372D01*
X834652Y448205D01*
X836318Y448413D01*
X837777Y448205D01*
X839027Y447372D01*
X839652Y445913D01*
Y440080D01*
G01X851610D02*
X850360Y440288D01*
X849110Y441121D01*
X848276Y442580D01*
X847860Y444247D01*
X848276Y445913D01*
X849110Y447372D01*
X850360Y448205D01*
X851610Y448413D01*
X852860Y448205D01*
X854110Y447372D01*
X854943Y445913D01*
X855152Y444247D01*
X854943Y442580D01*
X854110Y441121D01*
X852860Y440288D01*
X851610Y440080D01*
G01X864193D02*
Y448413D01*
G01Y446747D02*
X865235Y447580D01*
X866277Y448205D01*
X867735Y448413D01*
X868777Y448205D01*
X870027Y447580D01*
G01X879485Y445705D02*
X886152D01*
X885527Y447163D01*
X884485Y447997D01*
X883027Y448413D01*
X881568Y448205D01*
X880318Y447580D01*
X879485Y446122D01*
X879068Y444871D01*
Y443622D01*
X879485Y442372D01*
X880527Y441121D01*
X881777Y440288D01*
X883235Y440080D01*
X884693Y440497D01*
X886152Y441746D01*
G01X913610Y440080D02*
Y452580D01*
X911110Y450080D01*
G01Y440080D02*
X916110D01*
G01X938360D02*
Y448413D01*
G01Y446122D02*
X938985Y447163D01*
X940027Y447997D01*
X941485Y448413D01*
X942943Y447997D01*
X943985Y447163D01*
X944610Y446122D01*
Y440080D01*
G01Y446122D02*
X945235Y447163D01*
X946277Y447997D01*
X947735Y448413D01*
X949193Y447997D01*
X950235Y447163D01*
X950860Y445913D01*
Y440080D01*
G01X960110Y448413D02*
Y440080D01*
G01Y451746D02*
X959693Y451955D01*
Y452372D01*
X960110Y452580D01*
X960527Y452372D01*
Y451955D01*
X960110Y451746D01*
G01X975610Y440080D02*
Y452580D01*
G01X1002027Y440080D02*
Y452580D01*
X1006193D01*
X1007860Y451955D01*
X1009110Y451122D01*
X1010152Y449872D01*
X1010985Y448413D01*
X1011193Y446330D01*
X1010985Y444247D01*
X1010152Y442788D01*
X1009110Y441538D01*
X1007860Y440705D01*
X1006193Y440080D01*
X1002027D01*
G01X1019402Y444247D02*
X1024818D01*
G01X1042193Y451538D02*
X1040943Y452163D01*
X1039485Y452580D01*
X1037818D01*
X1035943Y451955D01*
X1034485Y450913D01*
X1033443Y449663D01*
X1032610Y447580D01*
X1032401Y445705D01*
X1032818Y443830D01*
X1033443Y442580D01*
X1034693Y441330D01*
X1036152Y440497D01*
X1037610Y440080D01*
X1039068D01*
X1040527Y440497D01*
X1041777Y441121D01*
X1042819Y441955D01*
G01X1053110Y440080D02*
X1051443Y440288D01*
X1049985Y441121D01*
X1048735Y442372D01*
X1047901Y443830D01*
X1047485Y445497D01*
Y447163D01*
X1047901Y448830D01*
X1048735Y450288D01*
X1049985Y451538D01*
X1051443Y452372D01*
X1053110Y452580D01*
X1054777Y452372D01*
X1056235Y451538D01*
X1057485Y450288D01*
X1058319Y448830D01*
X1058735Y447163D01*
Y445497D01*
X1058319Y443830D01*
X1057485Y442372D01*
X1056235Y441121D01*
X1054777Y440288D01*
X1053110Y440080D01*
G01X1064027D02*
Y452580D01*
X1068193D01*
X1069860Y451955D01*
X1071110Y451122D01*
X1072152Y449872D01*
X1072985Y448413D01*
X1073193Y446330D01*
X1072985Y444247D01*
X1072152Y442788D01*
X1071110Y441538D01*
X1069860Y440705D01*
X1068193Y440080D01*
X1064027D01*
G01X1088277D02*
X1079943D01*
Y452580D01*
X1088277D01*
G01X1084943Y446538D02*
X1079943D01*
G01X711718Y484980D02*
Y497480D01*
X721302Y484980D01*
Y497480D01*
G01X732010Y484980D02*
X730760Y485188D01*
X729510Y486021D01*
X728676Y487480D01*
X728260Y489147D01*
X728676Y490813D01*
X729510Y492272D01*
X730760Y493105D01*
X732010Y493313D01*
X733260Y493105D01*
X734510Y492272D01*
X735343Y490813D01*
X735552Y489147D01*
X735343Y487480D01*
X734510Y486021D01*
X733260Y485188D01*
X732010Y484980D01*
G01X747510Y497480D02*
Y484980D01*
G01X744593Y493313D02*
X750427D01*
G01X759885Y490605D02*
X766552D01*
X765927Y492063D01*
X764885Y492897D01*
X763427Y493313D01*
X761968Y493105D01*
X760718Y492480D01*
X759885Y491022D01*
X759468Y489771D01*
Y488522D01*
X759885Y487272D01*
X760927Y486021D01*
X762177Y485188D01*
X763635Y484980D01*
X765093Y485397D01*
X766552Y486646D01*
G01X775385Y486438D02*
X776427Y485605D01*
X777885Y484980D01*
X779135D01*
X780385Y485397D01*
X781218Y486021D01*
X781635Y486855D01*
X781427Y488105D01*
X780593Y488730D01*
X776843Y489980D01*
X776010Y491438D01*
X776427Y492480D01*
X777260Y493105D01*
X778510Y493313D01*
X779760Y493105D01*
X781010Y492480D01*
G01X794010Y484563D02*
X793593Y484772D01*
Y485188D01*
X794010Y485397D01*
X794427Y485188D01*
Y484772D01*
X794010Y484563D01*
G01Y490188D02*
X793593Y490397D01*
Y490813D01*
X794010Y491022D01*
X794427Y490813D01*
Y490397D01*
X794010Y490188D01*
G01X1407201Y955680D02*
X1412410Y943180D01*
X1417619Y955680D01*
G01X1427910Y943180D02*
Y955680D01*
X1425410Y953180D01*
G01Y943180D02*
X1430410D01*
G01X1443410Y942763D02*
X1442993Y942972D01*
Y943388D01*
X1443410Y943597D01*
X1443827Y943388D01*
Y942972D01*
X1443410Y942763D01*
G01X1458910Y955680D02*
X1457243Y955263D01*
X1455993Y954222D01*
X1455160Y952972D01*
X1454535Y951305D01*
X1454327Y949430D01*
X1454535Y947555D01*
X1455160Y945888D01*
X1455993Y944638D01*
X1457243Y943597D01*
X1458910Y943180D01*
X1460577Y943597D01*
X1461827Y944638D01*
X1462660Y945888D01*
X1463285Y947555D01*
X1463493Y949430D01*
X1463285Y951305D01*
X1462660Y952972D01*
X1461827Y954222D01*
X1460577Y955263D01*
X1458910Y955680D01*
G54D11*
G01X40093Y668280D02*
X33427D01*
Y678280D01*
X40093D01*
G01X37427Y673447D02*
X33427D01*
G01X44560Y668280D02*
X51560Y678280D01*
G01X44560D02*
X51560Y668280D01*
G01X59360Y667947D02*
X59027Y668113D01*
Y668447D01*
X59360Y668613D01*
X59693Y668447D01*
Y668113D01*
X59360Y667947D01*
G01Y672446D02*
X59027Y672613D01*
Y672947D01*
X59360Y673113D01*
X59693Y672947D01*
Y672613D01*
X59360Y672446D01*
G01X78793Y668280D02*
Y678280D01*
X85127D01*
G01X82793Y673447D02*
X78793D01*
G01X89927Y678280D02*
Y668280D01*
X96593D01*
G01X100393D02*
X104560Y678280D01*
X108727Y668280D01*
G01X107227Y671780D02*
X101893D01*
G01X112360Y669613D02*
X113693Y668780D01*
X115193Y668280D01*
X116527D01*
X117860Y668780D01*
X118860Y669613D01*
X119360Y670780D01*
X119027Y671946D01*
X118193Y672947D01*
X116693Y673613D01*
X114693Y673947D01*
X113527Y674613D01*
X113027Y675780D01*
X113360Y676947D01*
X114193Y677780D01*
X115360Y678280D01*
X116527D01*
X117693Y677947D01*
X118693Y677113D01*
G01X123660Y668280D02*
Y678280D01*
G01X130660D02*
Y668280D01*
G01Y673280D02*
X123660D01*
G01X149760Y678280D02*
Y668280D01*
G01X145927Y678280D02*
X153593D01*
G01X157727Y668280D02*
Y678280D01*
X161893D01*
X163227Y677780D01*
X164060Y677113D01*
X164393Y675780D01*
X164060Y674447D01*
X163060Y673613D01*
X161893Y673113D01*
X157727D01*
G01X161893D02*
X164393Y668280D01*
G01X172360D02*
Y678280D01*
X170360Y676280D01*
G01Y668280D02*
X174360D01*
G01X183660Y678280D02*
X182326Y677947D01*
X181327Y677113D01*
X180660Y676113D01*
X180160Y674780D01*
X179993Y673280D01*
X180160Y671780D01*
X180660Y670447D01*
X181327Y669446D01*
X182326Y668613D01*
X183660Y668280D01*
X184993Y668613D01*
X185993Y669446D01*
X186660Y670447D01*
X187160Y671780D01*
X187327Y673280D01*
X187160Y674780D01*
X186660Y676113D01*
X185993Y677113D01*
X184993Y677947D01*
X183660Y678280D01*
G01X191293Y670280D02*
X192293Y669113D01*
X193626Y668447D01*
X195127Y668280D01*
X196460Y668447D01*
X197793Y669280D01*
X198627Y670280D01*
X198793Y671280D01*
X198460Y672446D01*
X197293Y673280D01*
X196127Y673613D01*
X194627D01*
G01X196127D02*
X197127Y674113D01*
X197960Y674946D01*
X198293Y675947D01*
X197960Y676947D01*
X197127Y677780D01*
X195627Y678280D01*
X194127Y678113D01*
X192627Y677447D01*
G01X201260Y664947D02*
X211260D01*
G01X214727Y669446D02*
X215893Y668613D01*
X217227Y668280D01*
X218560Y668613D01*
X219727Y669613D01*
X220560Y671113D01*
X220893Y672613D01*
Y674447D01*
X220560Y675947D01*
X219727Y677280D01*
X218727Y677947D01*
X217560Y678280D01*
X216226Y677947D01*
X215227Y677280D01*
X214560Y676280D01*
X214227Y674946D01*
X214560Y673780D01*
X215393Y672613D01*
X216393Y671946D01*
X217560Y671780D01*
X218893Y672113D01*
X219893Y672947D01*
X220893Y674447D01*
G01X225193Y670280D02*
X226193Y669113D01*
X227526Y668447D01*
X229027Y668280D01*
X230360Y668447D01*
X231693Y669280D01*
X232527Y670280D01*
X232693Y671280D01*
X232360Y672446D01*
X231193Y673280D01*
X230027Y673613D01*
X228527D01*
G01X230027D02*
X231027Y674113D01*
X231860Y674946D01*
X232193Y675947D01*
X231860Y676947D01*
X231027Y677780D01*
X229527Y678280D01*
X228027Y678113D01*
X226527Y677447D01*
G01X235160Y664947D02*
X245160D01*
G01X247793Y670280D02*
X248793Y669113D01*
X250126Y668447D01*
X251627Y668280D01*
X252960Y668447D01*
X254293Y669280D01*
X255127Y670280D01*
X255293Y671280D01*
X254960Y672446D01*
X253793Y673280D01*
X252627Y673613D01*
X251127D01*
G01X252627D02*
X253627Y674113D01*
X254460Y674946D01*
X254793Y675947D01*
X254460Y676947D01*
X253627Y677780D01*
X252127Y678280D01*
X250627Y678113D01*
X249127Y677447D01*
G01X262760Y678280D02*
X261426Y677947D01*
X260427Y677113D01*
X259760Y676113D01*
X259260Y674780D01*
X259093Y673280D01*
X259260Y671780D01*
X259760Y670447D01*
X260427Y669446D01*
X261426Y668613D01*
X262760Y668280D01*
X264093Y668613D01*
X265093Y669446D01*
X265760Y670447D01*
X266260Y671780D01*
X266427Y673280D01*
X266260Y674780D01*
X265760Y676113D01*
X265093Y677113D01*
X264093Y677947D01*
X262760Y678280D01*
G01X274060Y667947D02*
X273727Y668113D01*
Y668447D01*
X274060Y668613D01*
X274393Y668447D01*
Y668113D01*
X274060Y667947D01*
G01Y672446D02*
X273727Y672613D01*
Y672947D01*
X274060Y673113D01*
X274393Y672947D01*
Y672613D01*
X274060Y672446D01*
G01X47093Y810280D02*
X48093Y809113D01*
X49426Y808447D01*
X50927Y808280D01*
X52260Y808447D01*
X53593Y809280D01*
X54427Y810280D01*
X54593Y811280D01*
X54260Y812446D01*
X53093Y813280D01*
X51927Y813613D01*
X50427D01*
G01X51927D02*
X52927Y814113D01*
X53760Y814946D01*
X54093Y815947D01*
X53760Y816947D01*
X52927Y817780D01*
X51427Y818280D01*
X49927Y818113D01*
X48427Y817447D01*
G01X62060Y807947D02*
X61727Y808113D01*
Y808447D01*
X62060Y808613D01*
X62393Y808447D01*
Y808113D01*
X62060Y807947D01*
G01X47593Y832613D02*
X48593Y833613D01*
X49760Y834113D01*
X51093Y834280D01*
X52760Y833947D01*
X53927Y833113D01*
X54260Y832113D01*
X54093Y831113D01*
X53427Y830280D01*
X50093Y828613D01*
X48593Y827447D01*
X47593Y825780D01*
X47260Y824280D01*
X54260D01*
G01X62060Y823947D02*
X61727Y824113D01*
Y824447D01*
X62060Y824613D01*
X62393Y824447D01*
Y824113D01*
X62060Y823947D01*
G01X50760Y840280D02*
Y850280D01*
X48760Y848280D01*
G01Y840280D02*
X52760D01*
G01X62060Y839947D02*
X61727Y840113D01*
Y840447D01*
X62060Y840613D01*
X62393Y840447D01*
Y840113D01*
X62060Y839947D01*
G01X81493Y840280D02*
Y850280D01*
X87827D01*
G01X85493Y845447D02*
X81493D01*
G01X92627Y850280D02*
Y840280D01*
X99293D01*
G01X103093D02*
X107260Y850280D01*
X111427Y840280D01*
G01X109927Y843780D02*
X104593D01*
G01X115060Y841613D02*
X116393Y840780D01*
X117893Y840280D01*
X119227D01*
X120560Y840780D01*
X121560Y841613D01*
X122060Y842780D01*
X121727Y843946D01*
X120893Y844947D01*
X119393Y845613D01*
X117393Y845947D01*
X116227Y846613D01*
X115727Y847780D01*
X116060Y848947D01*
X116893Y849780D01*
X118060Y850280D01*
X119227D01*
X120393Y849947D01*
X121393Y849113D01*
G01X126360Y840280D02*
Y850280D01*
G01X133360D02*
Y840280D01*
G01Y845280D02*
X126360D01*
G01X152460Y850280D02*
Y840280D01*
G01X148627Y850280D02*
X156293D01*
G01X160260Y840280D02*
Y850280D01*
G01X167260D02*
Y840280D01*
G01Y845280D02*
X160260D01*
G01X170727Y840280D02*
Y850280D01*
X175060Y841947D01*
X179393Y850280D01*
Y840280D01*
G01X183027Y850280D02*
Y840280D01*
X189693D01*
G01X197660D02*
Y850280D01*
X195660Y848280D01*
G01Y840280D02*
X199660D01*
G01X208960Y850280D02*
X207626Y849947D01*
X206627Y849113D01*
X205960Y848113D01*
X205460Y846780D01*
X205293Y845280D01*
X205460Y843780D01*
X205960Y842447D01*
X206627Y841446D01*
X207626Y840613D01*
X208960Y840280D01*
X210293Y840613D01*
X211293Y841446D01*
X211960Y842447D01*
X212460Y843780D01*
X212627Y845280D01*
X212460Y846780D01*
X211960Y848113D01*
X211293Y849113D01*
X210293Y849947D01*
X208960Y850280D01*
G01X231560Y839947D02*
X231227Y840113D01*
Y840447D01*
X231560Y840613D01*
X231893Y840447D01*
Y840113D01*
X231560Y839947D01*
G01Y844446D02*
X231227Y844613D01*
Y844947D01*
X231560Y845113D01*
X231893Y844947D01*
Y844613D01*
X231560Y844446D01*
G01X250993Y840280D02*
Y850280D01*
X257327D01*
G01X254993Y845447D02*
X250993D01*
G01X262627Y846946D02*
Y842280D01*
X263293Y841113D01*
X264293Y840447D01*
X265460Y840280D01*
X266627Y840447D01*
X267627Y841113D01*
X268293Y842280D01*
G01Y840280D02*
Y846946D01*
G01X276760Y840280D02*
Y850280D01*
G01X288060Y840280D02*
Y850280D01*
G01X313327Y846113D02*
X312160Y846780D01*
X311160Y846946D01*
X309827Y846613D01*
X308827Y845947D01*
X308160Y844780D01*
X307993Y843613D01*
X308160Y842447D01*
X308827Y841446D01*
X309827Y840613D01*
X311160Y840280D01*
X312327Y840613D01*
X313327Y841280D01*
G01X321960Y840280D02*
X320960Y840447D01*
X319960Y841113D01*
X319293Y842280D01*
X318960Y843613D01*
X319293Y844947D01*
X319960Y846113D01*
X320960Y846780D01*
X321960Y846946D01*
X322960Y846780D01*
X323960Y846113D01*
X324627Y844947D01*
X324793Y843613D01*
X324627Y842280D01*
X323960Y841113D01*
X322960Y840447D01*
X321960Y840280D01*
G01X330427D02*
Y846946D01*
G01Y845280D02*
X331093Y846113D01*
X332093Y846780D01*
X333427Y846946D01*
X334593Y846780D01*
X335593Y846113D01*
X336093Y844947D01*
Y840280D01*
G01X344560Y850280D02*
Y840280D01*
G01X342227Y846946D02*
X346893D01*
G01X358860Y840280D02*
Y846946D01*
G01Y845780D02*
X358193Y846447D01*
X357193Y846780D01*
X356027Y846946D01*
X354860Y846613D01*
X353860Y845947D01*
X353193Y844947D01*
X352860Y843613D01*
X353193Y842280D01*
X353860Y841280D01*
X354860Y840613D01*
X356027Y840280D01*
X357193Y840447D01*
X358193Y840947D01*
X358860Y841613D01*
G01X369827Y846113D02*
X368660Y846780D01*
X367660Y846946D01*
X366327Y846613D01*
X365327Y845947D01*
X364660Y844780D01*
X364493Y843613D01*
X364660Y842447D01*
X365327Y841446D01*
X366327Y840613D01*
X367660Y840280D01*
X368827Y840613D01*
X369827Y841280D01*
G01X378460Y850280D02*
Y840280D01*
G01X376127Y846946D02*
X380793D01*
G01X79760Y832280D02*
X82093Y822280D01*
X84760Y832280D01*
X87427Y822280D01*
X89760Y832280D01*
G01X96060Y828946D02*
Y822280D01*
G01Y831613D02*
X95727Y831780D01*
Y832113D01*
X96060Y832280D01*
X96393Y832113D01*
Y831780D01*
X96060Y831613D01*
G01X104860Y823446D02*
X105693Y822780D01*
X106860Y822280D01*
X107860D01*
X108860Y822613D01*
X109527Y823113D01*
X109860Y823780D01*
X109693Y824780D01*
X109027Y825280D01*
X106026Y826280D01*
X105360Y827447D01*
X105693Y828280D01*
X106360Y828780D01*
X107360Y828946D01*
X108360Y828780D01*
X109360Y828280D01*
G01X118660Y832280D02*
Y822280D01*
G01X116327Y828946D02*
X120993D01*
G01X127627Y822280D02*
Y828946D01*
G01Y827613D02*
X128460Y828280D01*
X129293Y828780D01*
X130460Y828946D01*
X131293Y828780D01*
X132293Y828280D01*
G01X141260Y822280D02*
X140260Y822447D01*
X139260Y823113D01*
X138593Y824280D01*
X138260Y825613D01*
X138593Y826947D01*
X139260Y828113D01*
X140260Y828780D01*
X141260Y828946D01*
X142260Y828780D01*
X143260Y828113D01*
X143927Y826947D01*
X144093Y825613D01*
X143927Y824280D01*
X143260Y823113D01*
X142260Y822447D01*
X141260Y822280D01*
G01X149727D02*
Y828946D01*
G01Y827280D02*
X150393Y828113D01*
X151393Y828780D01*
X152727Y828946D01*
X153893Y828780D01*
X154893Y828113D01*
X155393Y826947D01*
Y822280D01*
G01X175160Y832280D02*
Y822280D01*
G01X171327Y832280D02*
X178993D01*
G01X182960Y822280D02*
Y832280D01*
G01X189960D02*
Y822280D01*
G01Y827280D02*
X182960D01*
G01X193427Y822280D02*
Y832280D01*
X197760Y823947D01*
X202093Y832280D01*
Y822280D01*
G01X205727Y832280D02*
Y822280D01*
X212393D01*
G01X234660Y832280D02*
Y822280D01*
G01Y823780D02*
X233993Y822947D01*
X232993Y822447D01*
X231827Y822280D01*
X230493Y822613D01*
X229493Y823446D01*
X228827Y824447D01*
X228660Y825613D01*
X228827Y826780D01*
X229493Y827780D01*
X230493Y828613D01*
X231827Y828946D01*
X232993Y828780D01*
X233827Y828447D01*
X234660Y827780D01*
G01X240460Y826780D02*
X245793D01*
X245293Y827947D01*
X244460Y828613D01*
X243293Y828946D01*
X242127Y828780D01*
X241127Y828280D01*
X240460Y827113D01*
X240127Y826113D01*
Y825113D01*
X240460Y824113D01*
X241293Y823113D01*
X242293Y822447D01*
X243460Y822280D01*
X244627Y822613D01*
X245793Y823613D01*
G01X253260Y822280D02*
Y830780D01*
X253593Y831613D01*
X254260Y832113D01*
X255260Y832280D01*
X256260Y831947D01*
X256760Y831113D01*
G01X254760Y828280D02*
X251427D01*
G01X268560Y822280D02*
Y828946D01*
G01Y827780D02*
X267893Y828447D01*
X266893Y828780D01*
X265727Y828946D01*
X264560Y828613D01*
X263560Y827947D01*
X262893Y826947D01*
X262560Y825613D01*
X262893Y824280D01*
X263560Y823280D01*
X264560Y822613D01*
X265727Y822280D01*
X266893Y822447D01*
X267893Y822947D01*
X268560Y823613D01*
G01X274027Y828946D02*
Y824280D01*
X274693Y823113D01*
X275693Y822447D01*
X276860Y822280D01*
X278027Y822447D01*
X279027Y823113D01*
X279693Y824280D01*
G01Y822280D02*
Y828946D01*
G01X288160Y822280D02*
Y832280D01*
G01X299460D02*
Y822280D01*
G01X297127Y828946D02*
X301793D01*
G01X322060Y832280D02*
Y822280D01*
G01X319727Y828946D02*
X324393D01*
G01X329860Y819280D02*
X330860Y818947D01*
X332193Y819280D01*
X333027Y819947D01*
X333693Y820780D01*
X334693Y823446D01*
X336860Y828946D01*
G01X331527D02*
X334693Y823446D01*
G01X341660Y818947D02*
Y828946D01*
G01Y827447D02*
X342493Y828280D01*
X343326Y828780D01*
X344660Y828946D01*
X345827Y828780D01*
X346993Y827947D01*
X347493Y826780D01*
X347660Y825613D01*
X347493Y824447D01*
X346993Y823280D01*
X345993Y822613D01*
X344660Y822280D01*
X343493Y822447D01*
X342327Y822947D01*
X341660Y823613D01*
G01X353460Y826780D02*
X358793D01*
X358293Y827947D01*
X357460Y828613D01*
X356293Y828946D01*
X355127Y828780D01*
X354127Y828280D01*
X353460Y827113D01*
X353127Y826113D01*
Y825113D01*
X353460Y824113D01*
X354293Y823113D01*
X355293Y822447D01*
X356460Y822280D01*
X357627Y822613D01*
X358793Y823613D01*
G01X96393Y147580D02*
X89727D01*
Y157580D01*
X96393D01*
G01X93727Y152747D02*
X89727D01*
G01X100860Y147580D02*
X107860Y157580D01*
G01X100860D02*
X107860Y147580D01*
G01X115660Y147247D02*
X115327Y147413D01*
Y147747D01*
X115660Y147913D01*
X115993Y147747D01*
Y147413D01*
X115660Y147247D01*
G01Y151746D02*
X115327Y151913D01*
Y152247D01*
X115660Y152413D01*
X115993Y152247D01*
Y151913D01*
X115660Y151746D01*
G01X135093Y147580D02*
Y157580D01*
X141427D01*
G01X139093Y152747D02*
X135093D01*
G01X146227Y157580D02*
Y147580D01*
X152893D01*
G01X156693D02*
X160860Y157580D01*
X165027Y147580D01*
G01X163527Y151080D02*
X158193D01*
G01X168660Y148913D02*
X169993Y148080D01*
X171493Y147580D01*
X172827D01*
X174160Y148080D01*
X175160Y148913D01*
X175660Y150080D01*
X175327Y151246D01*
X174493Y152247D01*
X172993Y152913D01*
X170993Y153247D01*
X169827Y153913D01*
X169327Y155080D01*
X169660Y156247D01*
X170493Y157080D01*
X171660Y157580D01*
X172827D01*
X173993Y157247D01*
X174993Y156413D01*
G01X179960Y147580D02*
Y157580D01*
G01X186960D02*
Y147580D01*
G01Y152580D02*
X179960D01*
G01X206060Y157580D02*
Y147580D01*
G01X202227Y157580D02*
X209893D01*
G01X214027Y147580D02*
Y157580D01*
X218193D01*
X219527Y157080D01*
X220360Y156413D01*
X220693Y155080D01*
X220360Y153747D01*
X219360Y152913D01*
X218193Y152413D01*
X214027D01*
G01X218193D02*
X220693Y147580D01*
G01X225493Y151746D02*
X226660Y152913D01*
X227660Y153580D01*
X228993Y153913D01*
X230160Y153580D01*
X230993Y152913D01*
X231660Y151913D01*
X231827Y150747D01*
X231660Y149747D01*
X230993Y148746D01*
X229993Y147913D01*
X228827Y147580D01*
X227493Y147913D01*
X226327Y148913D01*
X225660Y150413D01*
X225493Y152080D01*
X225827Y154246D01*
X226327Y155413D01*
X227160Y156580D01*
X228327Y157413D01*
X229493Y157580D01*
X230660Y157247D01*
X231493Y156413D01*
G01X239960Y157580D02*
X238626Y157247D01*
X237627Y156413D01*
X236960Y155413D01*
X236460Y154080D01*
X236293Y152580D01*
X236460Y151080D01*
X236960Y149747D01*
X237627Y148746D01*
X238626Y147913D01*
X239960Y147580D01*
X241293Y147913D01*
X242293Y148746D01*
X242960Y149747D01*
X243460Y151080D01*
X243627Y152580D01*
X243460Y154080D01*
X242960Y155413D01*
X242293Y156413D01*
X241293Y157247D01*
X239960Y157580D01*
G01X247760Y147580D02*
X254760Y157580D01*
G01X247760D02*
X254760Y147580D01*
G01X262560D02*
Y157580D01*
X260560Y155580D01*
G01Y147580D02*
X264560D01*
G01X273860D02*
Y157580D01*
X271860Y155580D01*
G01Y147580D02*
X275860D01*
G01X282327Y148746D02*
X283493Y147913D01*
X284827Y147580D01*
X286160Y147913D01*
X287327Y148913D01*
X288160Y150413D01*
X288493Y151913D01*
Y153747D01*
X288160Y155247D01*
X287327Y156580D01*
X286327Y157247D01*
X285160Y157580D01*
X283826Y157247D01*
X282827Y156580D01*
X282160Y155580D01*
X281827Y154246D01*
X282160Y153080D01*
X282993Y151913D01*
X283993Y151246D01*
X285160Y151080D01*
X286493Y151413D01*
X287493Y152247D01*
X288493Y153747D01*
G01X291460Y144247D02*
X301460D01*
G01X304593Y155913D02*
X305593Y156913D01*
X306760Y157413D01*
X308093Y157580D01*
X309760Y157247D01*
X310927Y156413D01*
X311260Y155413D01*
X311093Y154413D01*
X310427Y153580D01*
X307093Y151913D01*
X305593Y150747D01*
X304593Y149080D01*
X304260Y147580D01*
X311260D01*
G01X319060Y157580D02*
X317726Y157247D01*
X316727Y156413D01*
X316060Y155413D01*
X315560Y154080D01*
X315393Y152580D01*
X315560Y151080D01*
X316060Y149747D01*
X316727Y148746D01*
X317726Y147913D01*
X319060Y147580D01*
X320393Y147913D01*
X321393Y148746D01*
X322060Y149747D01*
X322560Y151080D01*
X322727Y152580D01*
X322560Y154080D01*
X322060Y155413D01*
X321393Y156413D01*
X320393Y157247D01*
X319060Y157580D01*
G01X326860Y147580D02*
X333860Y157580D01*
G01X326860D02*
X333860Y147580D01*
G01X337993Y149580D02*
X338993Y148413D01*
X340326Y147747D01*
X341827Y147580D01*
X343160Y147747D01*
X344493Y148580D01*
X345327Y149580D01*
X345493Y150580D01*
X345160Y151746D01*
X343993Y152580D01*
X342827Y152913D01*
X341327D01*
G01X342827D02*
X343827Y153413D01*
X344660Y154246D01*
X344993Y155247D01*
X344660Y156247D01*
X343827Y157080D01*
X342327Y157580D01*
X340827Y157413D01*
X339327Y156747D01*
G01X352960Y157580D02*
X351626Y157247D01*
X350627Y156413D01*
X349960Y155413D01*
X349460Y154080D01*
X349293Y152580D01*
X349460Y151080D01*
X349960Y149747D01*
X350627Y148746D01*
X351626Y147913D01*
X352960Y147580D01*
X354293Y147913D01*
X355293Y148746D01*
X355960Y149747D01*
X356460Y151080D01*
X356627Y152580D01*
X356460Y154080D01*
X355960Y155413D01*
X355293Y156413D01*
X354293Y157247D01*
X352960Y157580D01*
G01X86027Y197380D02*
Y207380D01*
X93693Y197380D01*
Y207380D01*
G01X96993Y197380D02*
X101160Y207380D01*
X105327Y197380D01*
G01X103827Y200880D02*
X98493D01*
G01X108127Y197380D02*
Y207380D01*
X112460Y199047D01*
X116793Y207380D01*
Y197380D01*
G01X127093D02*
X120427D01*
Y207380D01*
X127093D01*
G01X124427Y202547D02*
X120427D01*
G01X135060Y197047D02*
X134727Y197213D01*
Y197547D01*
X135060Y197713D01*
X135393Y197547D01*
Y197213D01*
X135060Y197047D01*
G01Y201546D02*
X134727Y201713D01*
Y202047D01*
X135060Y202213D01*
X135393Y202047D01*
Y201713D01*
X135060Y201546D01*
G01X157660Y207380D02*
Y197380D01*
G01X153827Y207380D02*
X161493D01*
G01X165627Y197380D02*
Y207380D01*
X169793D01*
X171127Y206880D01*
X171960Y206213D01*
X172293Y204880D01*
X171960Y203547D01*
X170960Y202713D01*
X169793Y202213D01*
X165627D01*
G01X169793D02*
X172293Y197380D01*
G01X176093D02*
X180260Y207380D01*
X184427Y197380D01*
G01X182927Y200880D02*
X177593D01*
G01X188060Y197380D02*
X195060Y207380D01*
G01X188060D02*
X195060Y197380D01*
G01X204193Y202713D02*
X204860Y203213D01*
X205360Y204046D01*
X205693Y205213D01*
X205360Y206213D01*
X204693Y206880D01*
X203527Y207380D01*
X199027D01*
Y197380D01*
X204527D01*
X205693Y198047D01*
X206360Y199047D01*
X206693Y200213D01*
X206360Y201380D01*
X205360Y202380D01*
X204193Y202713D01*
X199027D01*
G01X209160Y194047D02*
X219160D01*
G01X229127Y206547D02*
X228127Y207047D01*
X226960Y207380D01*
X225627D01*
X224126Y206880D01*
X222960Y206047D01*
X222127Y205047D01*
X221460Y203380D01*
X221293Y201880D01*
X221627Y200380D01*
X222127Y199380D01*
X223127Y198380D01*
X224293Y197713D01*
X225460Y197380D01*
X226627D01*
X227793Y197713D01*
X228793Y198213D01*
X229627Y198880D01*
G01X233260Y197380D02*
X240260Y207380D01*
G01X233260D02*
X240260Y197380D01*
G01X244393D02*
Y207380D01*
X247727D01*
X249060Y206880D01*
X250060Y206213D01*
X250893Y205213D01*
X251560Y204046D01*
X251727Y202380D01*
X251560Y200713D01*
X250893Y199547D01*
X250060Y198546D01*
X249060Y197880D01*
X247727Y197380D01*
X244393D01*
G01X113093Y173580D02*
X106427D01*
Y183580D01*
X113093D01*
G01X110427Y178747D02*
X106427D01*
G01X121060Y173247D02*
X120727Y173413D01*
Y173747D01*
X121060Y173913D01*
X121393Y173747D01*
Y173413D01*
X121060Y173247D01*
G01Y177746D02*
X120727Y177913D01*
Y178247D01*
X121060Y178413D01*
X121393Y178247D01*
Y177913D01*
X121060Y177746D01*
G01X112293Y341980D02*
Y351980D01*
X115627D01*
X116960Y351480D01*
X117960Y350813D01*
X118793Y349813D01*
X119460Y348646D01*
X119627Y346980D01*
X119460Y345313D01*
X118793Y344147D01*
X117960Y343146D01*
X116960Y342480D01*
X115627Y341980D01*
X112293D01*
G01X123993Y463580D02*
X117327D01*
Y473580D01*
X123993D01*
G01X121327Y468747D02*
X117327D01*
G01X128627Y473580D02*
Y463580D01*
X135293D01*
G01X139927Y473580D02*
Y463580D01*
X146593D01*
G01X152560Y473580D02*
X156560D01*
G01X154560D02*
Y463580D01*
G01X152560D02*
X156560D01*
G01X162527D02*
Y473580D01*
X166527D01*
X167860Y473080D01*
X168860Y471913D01*
X169193Y470580D01*
X168860Y469247D01*
X168027Y468247D01*
X166527Y467746D01*
X162527D01*
G01X173660Y464913D02*
X174993Y464080D01*
X176493Y463580D01*
X177827D01*
X179160Y464080D01*
X180160Y464913D01*
X180660Y466080D01*
X180327Y467246D01*
X179493Y468247D01*
X177993Y468913D01*
X175993Y469247D01*
X174827Y469913D01*
X174327Y471080D01*
X174660Y472247D01*
X175493Y473080D01*
X176660Y473580D01*
X177827D01*
X178993Y473247D01*
X179993Y472413D01*
G01X191793Y463580D02*
X185127D01*
Y473580D01*
X191793D01*
G01X189127Y468747D02*
X185127D01*
G01X211060Y473580D02*
Y463580D01*
G01X207227Y473580D02*
X214893D01*
G01X219527Y463580D02*
Y473580D01*
G01Y468747D02*
X220360Y469580D01*
X221193Y470080D01*
X222527Y470246D01*
X223527Y470080D01*
X224693Y469413D01*
X225193Y468413D01*
Y463580D01*
G01X231160Y468080D02*
X236493D01*
X235993Y469247D01*
X235160Y469913D01*
X233993Y470246D01*
X232827Y470080D01*
X231827Y469580D01*
X231160Y468413D01*
X230827Y467413D01*
Y466413D01*
X231160Y465413D01*
X231993Y464413D01*
X232993Y463747D01*
X234160Y463580D01*
X235327Y463913D01*
X236493Y464913D01*
G01X242627Y463580D02*
Y470246D01*
G01Y468913D02*
X243460Y469580D01*
X244293Y470080D01*
X245460Y470246D01*
X246293Y470080D01*
X247293Y469580D01*
G01X251260Y463580D02*
Y470246D01*
G01Y468413D02*
X251760Y469247D01*
X252593Y469913D01*
X253760Y470246D01*
X254926Y469913D01*
X255760Y469247D01*
X256260Y468413D01*
Y463580D01*
G01Y468413D02*
X256760Y469247D01*
X257593Y469913D01*
X258760Y470246D01*
X259927Y469913D01*
X260760Y469247D01*
X261260Y468247D01*
Y463580D01*
G01X270560D02*
Y470246D01*
G01Y469080D02*
X269893Y469747D01*
X268893Y470080D01*
X267727Y470246D01*
X266560Y469913D01*
X265560Y469247D01*
X264893Y468247D01*
X264560Y466913D01*
X264893Y465580D01*
X265560Y464580D01*
X266560Y463913D01*
X267727Y463580D01*
X268893Y463747D01*
X269893Y464247D01*
X270560Y464913D01*
G01X278860Y463580D02*
Y473580D01*
G01X125593Y262980D02*
X118927D01*
Y272980D01*
X125593D01*
G01X122927Y268147D02*
X118927D01*
G01X122460Y705480D02*
X126460D01*
G01X124460D02*
Y695480D01*
G01X122460D02*
X126460D01*
G01X132927D02*
Y702146D01*
G01Y700480D02*
X133593Y701313D01*
X134593Y701980D01*
X135927Y702146D01*
X137093Y701980D01*
X138093Y701313D01*
X138593Y700147D01*
Y695480D01*
G01X144227D02*
Y702146D01*
G01Y700480D02*
X144893Y701313D01*
X145893Y701980D01*
X147227Y702146D01*
X148393Y701980D01*
X149393Y701313D01*
X149893Y700147D01*
Y695480D01*
G01X155860Y699980D02*
X161193D01*
X160693Y701147D01*
X159860Y701813D01*
X158693Y702146D01*
X157527Y701980D01*
X156527Y701480D01*
X155860Y700313D01*
X155527Y699313D01*
Y698313D01*
X155860Y697313D01*
X156693Y696313D01*
X157693Y695647D01*
X158860Y695480D01*
X160027Y695813D01*
X161193Y696813D01*
G01X167327Y695480D02*
Y702146D01*
G01Y700813D02*
X168160Y701480D01*
X168993Y701980D01*
X170160Y702146D01*
X170993Y701980D01*
X171993Y701480D01*
G01X188593Y695480D02*
Y705480D01*
X191927D01*
X193260Y704980D01*
X194260Y704313D01*
X195093Y703313D01*
X195760Y702146D01*
X195927Y700480D01*
X195760Y698813D01*
X195093Y697647D01*
X194260Y696646D01*
X193260Y695980D01*
X191927Y695480D01*
X188593D01*
G01X203560Y702146D02*
Y695480D01*
G01Y704813D02*
X203227Y704980D01*
Y705313D01*
X203560Y705480D01*
X203893Y705313D01*
Y704980D01*
X203560Y704813D01*
G01X217860Y695480D02*
Y702146D01*
G01Y700980D02*
X217193Y701647D01*
X216193Y701980D01*
X215027Y702146D01*
X213860Y701813D01*
X212860Y701147D01*
X212193Y700147D01*
X211860Y698813D01*
X212193Y697480D01*
X212860Y696480D01*
X213860Y695813D01*
X215027Y695480D01*
X216193Y695647D01*
X217193Y696147D01*
X217860Y696813D01*
G01X221160Y695480D02*
Y702146D01*
G01Y700313D02*
X221660Y701147D01*
X222493Y701813D01*
X223660Y702146D01*
X224826Y701813D01*
X225660Y701147D01*
X226160Y700313D01*
Y695480D01*
G01Y700313D02*
X226660Y701147D01*
X227493Y701813D01*
X228660Y702146D01*
X229827Y701813D01*
X230660Y701147D01*
X231160Y700147D01*
Y695480D01*
G01X234960Y699980D02*
X240293D01*
X239793Y701147D01*
X238960Y701813D01*
X237793Y702146D01*
X236627Y701980D01*
X235627Y701480D01*
X234960Y700313D01*
X234627Y699313D01*
Y698313D01*
X234960Y697313D01*
X235793Y696313D01*
X236793Y695647D01*
X237960Y695480D01*
X239127Y695813D01*
X240293Y696813D01*
G01X248760Y705480D02*
Y695480D01*
G01X246427Y702146D02*
X251093D01*
G01X257560Y699980D02*
X262893D01*
X262393Y701147D01*
X261560Y701813D01*
X260393Y702146D01*
X259227Y701980D01*
X258227Y701480D01*
X257560Y700313D01*
X257227Y699313D01*
Y698313D01*
X257560Y697313D01*
X258393Y696313D01*
X259393Y695647D01*
X260560Y695480D01*
X261727Y695813D01*
X262893Y696813D01*
G01X269027Y695480D02*
Y702146D01*
G01Y700813D02*
X269860Y701480D01*
X270693Y701980D01*
X271860Y702146D01*
X272693Y701980D01*
X273693Y701480D01*
G01X161093Y173280D02*
X154427D01*
Y183280D01*
X161093D01*
G01X158427Y178447D02*
X154427D01*
G01X166893Y175113D02*
X171227D01*
G01Y178113D02*
X166893D01*
G01X176693Y174780D02*
X177693Y173947D01*
X178860Y173447D01*
X180360Y173280D01*
X181860Y173613D01*
X183027Y174280D01*
X183860Y175447D01*
X184027Y176780D01*
X183693Y178113D01*
X182860Y178947D01*
X181693Y179613D01*
X180527Y179780D01*
X179360Y179613D01*
X177860Y178947D01*
X178360Y183280D01*
X182860D01*
G01X198627Y173280D02*
Y183280D01*
X202960Y174947D01*
X207293Y183280D01*
Y173280D01*
G01X212260Y183280D02*
X216260D01*
G01X214260D02*
Y173280D01*
G01X212260D02*
X216260D01*
G01X222227Y183280D02*
Y173280D01*
X228893D01*
G01X233360Y174613D02*
X234693Y173780D01*
X236193Y173280D01*
X237527D01*
X238860Y173780D01*
X239860Y174613D01*
X240360Y175780D01*
X240027Y176946D01*
X239193Y177947D01*
X237693Y178613D01*
X235693Y178947D01*
X234527Y179613D01*
X234027Y180780D01*
X234360Y181947D01*
X235193Y182780D01*
X236360Y183280D01*
X237527D01*
X238693Y182947D01*
X239693Y182113D01*
G01X258627Y169947D02*
X256960Y171613D01*
X256127Y173280D01*
Y179946D01*
X256960Y181613D01*
X258627Y183280D01*
G01X273760Y173280D02*
Y179946D01*
G01Y178780D02*
X273093Y179447D01*
X272093Y179780D01*
X270927Y179946D01*
X269760Y179613D01*
X268760Y178947D01*
X268093Y177947D01*
X267760Y176613D01*
X268093Y175280D01*
X268760Y174280D01*
X269760Y173613D01*
X270927Y173280D01*
X272093Y173447D01*
X273093Y173947D01*
X273760Y174613D01*
G01X282060Y173280D02*
Y183280D01*
G01X289193Y179946D02*
X291193Y173280D01*
X293360Y179946D01*
X295527Y173280D01*
X297527Y179946D01*
G01X307660Y173280D02*
Y179946D01*
G01Y178780D02*
X306993Y179447D01*
X305993Y179780D01*
X304827Y179946D01*
X303660Y179613D01*
X302660Y178947D01*
X301993Y177947D01*
X301660Y176613D01*
X301993Y175280D01*
X302660Y174280D01*
X303660Y173613D01*
X304827Y173280D01*
X305993Y173447D01*
X306993Y173947D01*
X307660Y174613D01*
G01X312460Y170280D02*
X313460Y169947D01*
X314793Y170280D01*
X315627Y170947D01*
X316293Y171780D01*
X317293Y174446D01*
X319460Y179946D01*
G01X314127D02*
X317293Y174446D01*
G01X324760D02*
X325593Y173780D01*
X326760Y173280D01*
X327760D01*
X328760Y173613D01*
X329427Y174113D01*
X329760Y174780D01*
X329593Y175780D01*
X328927Y176280D01*
X325926Y177280D01*
X325260Y178447D01*
X325593Y179280D01*
X326260Y179780D01*
X327260Y179946D01*
X328260Y179780D01*
X329260Y179280D01*
G01X347027Y173280D02*
Y183280D01*
G01X352360Y179946D02*
X347027Y176113D01*
G01X349193Y177613D02*
X352693Y173280D01*
G01X358660Y177780D02*
X363993D01*
X363493Y178947D01*
X362660Y179613D01*
X361493Y179946D01*
X360327Y179780D01*
X359327Y179280D01*
X358660Y178113D01*
X358327Y177113D01*
Y176113D01*
X358660Y175113D01*
X359493Y174113D01*
X360493Y173447D01*
X361660Y173280D01*
X362827Y173613D01*
X363993Y174613D01*
G01X369960Y177780D02*
X375293D01*
X374793Y178947D01*
X373960Y179613D01*
X372793Y179946D01*
X371627Y179780D01*
X370627Y179280D01*
X369960Y178113D01*
X369627Y177113D01*
Y176113D01*
X369960Y175113D01*
X370793Y174113D01*
X371793Y173447D01*
X372960Y173280D01*
X374127Y173613D01*
X375293Y174613D01*
G01X380760Y169947D02*
Y179946D01*
G01Y178447D02*
X381593Y179280D01*
X382426Y179780D01*
X383760Y179946D01*
X384927Y179780D01*
X386093Y178947D01*
X386593Y177780D01*
X386760Y176613D01*
X386593Y175447D01*
X386093Y174280D01*
X385093Y173613D01*
X383760Y173280D01*
X382593Y173447D01*
X381427Y173947D01*
X380760Y174613D01*
G01X402693Y174780D02*
X403693Y173947D01*
X404860Y173447D01*
X406360Y173280D01*
X407860Y173613D01*
X409027Y174280D01*
X409860Y175447D01*
X410027Y176780D01*
X409693Y178113D01*
X408860Y178947D01*
X407693Y179613D01*
X406527Y179780D01*
X405360Y179613D01*
X403860Y178947D01*
X404360Y183280D01*
X408860D01*
G01X423960Y173280D02*
Y179946D01*
G01Y178113D02*
X424460Y178947D01*
X425293Y179613D01*
X426460Y179946D01*
X427626Y179613D01*
X428460Y178947D01*
X428960Y178113D01*
Y173280D01*
G01Y178113D02*
X429460Y178947D01*
X430293Y179613D01*
X431460Y179946D01*
X432627Y179613D01*
X433460Y178947D01*
X433960Y177947D01*
Y173280D01*
G01X440260Y179946D02*
Y173280D01*
G01Y182613D02*
X439927Y182780D01*
Y183113D01*
X440260Y183280D01*
X440593Y183113D01*
Y182780D01*
X440260Y182613D01*
G01X451560Y173280D02*
Y183280D01*
G01X460360Y174446D02*
X461193Y173780D01*
X462360Y173280D01*
X463360D01*
X464360Y173613D01*
X465027Y174113D01*
X465360Y174780D01*
X465193Y175780D01*
X464527Y176280D01*
X461526Y177280D01*
X460860Y178447D01*
X461193Y179280D01*
X461860Y179780D01*
X462860Y179946D01*
X463860Y179780D01*
X464860Y179280D01*
G01X474993Y169947D02*
X476660Y171613D01*
X477493Y173280D01*
Y179946D01*
X476660Y181613D01*
X474993Y183280D01*
G01X193827Y245647D02*
X192827Y246147D01*
X191660Y246480D01*
X190327D01*
X188826Y245980D01*
X187660Y245147D01*
X186827Y244147D01*
X186160Y242480D01*
X185993Y240980D01*
X186327Y239480D01*
X186827Y238480D01*
X187827Y237480D01*
X188993Y236813D01*
X190160Y236480D01*
X191327D01*
X192493Y236813D01*
X193493Y237313D01*
X194327Y237980D01*
G01X185693Y434080D02*
X189860Y444080D01*
X194027Y434080D01*
G01X192527Y437580D02*
X187193D01*
G01X217250Y752960D02*
X220583D01*
Y749960D01*
X219583Y748960D01*
X218417Y748293D01*
X216750Y747960D01*
X215083Y748293D01*
X213917Y748960D01*
X212917Y749960D01*
X212250Y751127D01*
X211917Y752460D01*
Y753627D01*
X212250Y754626D01*
X212917Y755793D01*
X213917Y756793D01*
X214916Y757460D01*
X216250Y757960D01*
X217417D01*
X218750Y757627D01*
X219750Y756960D01*
G01X230550Y747960D02*
Y754626D01*
G01Y753460D02*
X229883Y754127D01*
X228883Y754460D01*
X227717Y754626D01*
X226550Y754293D01*
X225550Y753627D01*
X224883Y752627D01*
X224550Y751293D01*
X224883Y749960D01*
X225550Y748960D01*
X226550Y748293D01*
X227717Y747960D01*
X228883Y748127D01*
X229883Y748627D01*
X230550Y749293D01*
G01X235850Y744627D02*
Y754626D01*
G01Y753127D02*
X236683Y753960D01*
X237516Y754460D01*
X238850Y754626D01*
X240017Y754460D01*
X241183Y753627D01*
X241683Y752460D01*
X241850Y751293D01*
X241683Y750127D01*
X241183Y748960D01*
X240183Y748293D01*
X238850Y747960D01*
X237683Y748127D01*
X236517Y748627D01*
X235850Y749293D01*
G01X256450Y757960D02*
X258783Y747960D01*
X261450Y757960D01*
X264117Y747960D01*
X266450Y757960D01*
G01X272750Y754626D02*
Y747960D01*
G01Y757293D02*
X272417Y757460D01*
Y757793D01*
X272750Y757960D01*
X273083Y757793D01*
Y757460D01*
X272750Y757293D01*
G01X287050Y757960D02*
Y747960D01*
G01Y749460D02*
X286383Y748627D01*
X285383Y748127D01*
X284217Y747960D01*
X282883Y748293D01*
X281883Y749126D01*
X281217Y750127D01*
X281050Y751293D01*
X281217Y752460D01*
X281883Y753460D01*
X282883Y754293D01*
X284217Y754626D01*
X285383Y754460D01*
X286217Y754127D01*
X287050Y753460D01*
G01X295350Y757960D02*
Y747960D01*
G01X293017Y754626D02*
X297683D01*
G01X303817Y747960D02*
Y757960D01*
G01Y753127D02*
X304650Y753960D01*
X305483Y754460D01*
X306817Y754626D01*
X307817Y754460D01*
X308983Y753793D01*
X309483Y752793D01*
Y747960D01*
G01X219690Y796560D02*
X218356Y796727D01*
X217190Y797393D01*
X216190Y798393D01*
X215523Y799560D01*
X215190Y800893D01*
Y802227D01*
X215523Y803560D01*
X216190Y804727D01*
X217190Y805727D01*
X218356Y806393D01*
X219690Y806560D01*
X221023Y806393D01*
X222190Y805727D01*
X223190Y804727D01*
X223857Y803560D01*
X224190Y802227D01*
Y800893D01*
X223857Y799560D01*
X223190Y798393D01*
X222190Y797393D01*
X221023Y796727D01*
X219690Y796560D01*
G01X228157Y803226D02*
Y798560D01*
X228823Y797393D01*
X229823Y796727D01*
X230990Y796560D01*
X232157Y796727D01*
X233157Y797393D01*
X233823Y798560D01*
G01Y796560D02*
Y803226D01*
G01X242290Y806560D02*
Y796560D01*
G01X239957Y803226D02*
X244623D01*
G01X251090Y801060D02*
X256423D01*
X255923Y802227D01*
X255090Y802893D01*
X253923Y803226D01*
X252757Y803060D01*
X251757Y802560D01*
X251090Y801393D01*
X250757Y800393D01*
Y799393D01*
X251090Y798393D01*
X251923Y797393D01*
X252923Y796727D01*
X254090Y796560D01*
X255257Y796893D01*
X256423Y797893D01*
G01X262557Y796560D02*
Y803226D01*
G01Y801893D02*
X263390Y802560D01*
X264223Y803060D01*
X265390Y803226D01*
X266223Y803060D01*
X267223Y802560D01*
G01X283823Y796560D02*
Y806560D01*
X287157D01*
X288490Y806060D01*
X289490Y805393D01*
X290323Y804393D01*
X290990Y803226D01*
X291157Y801560D01*
X290990Y799893D01*
X290323Y798727D01*
X289490Y797726D01*
X288490Y797060D01*
X287157Y796560D01*
X283823D01*
G01X298790Y803226D02*
Y796560D01*
G01Y805893D02*
X298457Y806060D01*
Y806393D01*
X298790Y806560D01*
X299123Y806393D01*
Y806060D01*
X298790Y805893D01*
G01X313090Y796560D02*
Y803226D01*
G01Y802060D02*
X312423Y802727D01*
X311423Y803060D01*
X310257Y803226D01*
X309090Y802893D01*
X308090Y802227D01*
X307423Y801227D01*
X307090Y799893D01*
X307423Y798560D01*
X308090Y797560D01*
X309090Y796893D01*
X310257Y796560D01*
X311423Y796727D01*
X312423Y797227D01*
X313090Y797893D01*
G01X316390Y796560D02*
Y803226D01*
G01Y801393D02*
X316890Y802227D01*
X317723Y802893D01*
X318890Y803226D01*
X320056Y802893D01*
X320890Y802227D01*
X321390Y801393D01*
Y796560D01*
G01Y801393D02*
X321890Y802227D01*
X322723Y802893D01*
X323890Y803226D01*
X325057Y802893D01*
X325890Y802227D01*
X326390Y801227D01*
Y796560D01*
G01X330190Y801060D02*
X335523D01*
X335023Y802227D01*
X334190Y802893D01*
X333023Y803226D01*
X331857Y803060D01*
X330857Y802560D01*
X330190Y801393D01*
X329857Y800393D01*
Y799393D01*
X330190Y798393D01*
X331023Y797393D01*
X332023Y796727D01*
X333190Y796560D01*
X334357Y796893D01*
X335523Y797893D01*
G01X343990Y806560D02*
Y796560D01*
G01X341657Y803226D02*
X346323D01*
G01X352790Y801060D02*
X358123D01*
X357623Y802227D01*
X356790Y802893D01*
X355623Y803226D01*
X354457Y803060D01*
X353457Y802560D01*
X352790Y801393D01*
X352457Y800393D01*
Y799393D01*
X352790Y798393D01*
X353623Y797393D01*
X354623Y796727D01*
X355790Y796560D01*
X356957Y796893D01*
X358123Y797893D01*
G01X364257Y796560D02*
Y803226D01*
G01Y801893D02*
X365090Y802560D01*
X365923Y803060D01*
X367090Y803226D01*
X367923Y803060D01*
X368923Y802560D01*
G01X258793Y347813D02*
X259460Y348313D01*
X259960Y349146D01*
X260293Y350313D01*
X259960Y351313D01*
X259293Y351980D01*
X258127Y352480D01*
X253627D01*
Y342480D01*
X259127D01*
X260293Y343147D01*
X260960Y344147D01*
X261293Y345313D01*
X260960Y346480D01*
X259960Y347480D01*
X258793Y347813D01*
X253627D01*
G01X282760Y676280D02*
X286760D01*
G01X284760D02*
Y666280D01*
G01X282760D02*
X286760D01*
G01X293227D02*
Y672946D01*
G01Y671280D02*
X293893Y672113D01*
X294893Y672780D01*
X296227Y672946D01*
X297393Y672780D01*
X298393Y672113D01*
X298893Y670947D01*
Y666280D01*
G01X304527D02*
Y672946D01*
G01Y671280D02*
X305193Y672113D01*
X306193Y672780D01*
X307527Y672946D01*
X308693Y672780D01*
X309693Y672113D01*
X310193Y670947D01*
Y666280D01*
G01X316160Y670780D02*
X321493D01*
X320993Y671947D01*
X320160Y672613D01*
X318993Y672946D01*
X317827Y672780D01*
X316827Y672280D01*
X316160Y671113D01*
X315827Y670113D01*
Y669113D01*
X316160Y668113D01*
X316993Y667113D01*
X317993Y666447D01*
X319160Y666280D01*
X320327Y666613D01*
X321493Y667613D01*
G01X327627Y666280D02*
Y672946D01*
G01Y671613D02*
X328460Y672280D01*
X329293Y672780D01*
X330460Y672946D01*
X331293Y672780D01*
X332293Y672280D01*
G01X348893Y666280D02*
Y676280D01*
X352227D01*
X353560Y675780D01*
X354560Y675113D01*
X355393Y674113D01*
X356060Y672946D01*
X356227Y671280D01*
X356060Y669613D01*
X355393Y668447D01*
X354560Y667446D01*
X353560Y666780D01*
X352227Y666280D01*
X348893D01*
G01X363860Y672946D02*
Y666280D01*
G01Y675613D02*
X363527Y675780D01*
Y676113D01*
X363860Y676280D01*
X364193Y676113D01*
Y675780D01*
X363860Y675613D01*
G01X378160Y666280D02*
Y672946D01*
G01Y671780D02*
X377493Y672447D01*
X376493Y672780D01*
X375327Y672946D01*
X374160Y672613D01*
X373160Y671947D01*
X372493Y670947D01*
X372160Y669613D01*
X372493Y668280D01*
X373160Y667280D01*
X374160Y666613D01*
X375327Y666280D01*
X376493Y666447D01*
X377493Y666947D01*
X378160Y667613D01*
G01X381460Y666280D02*
Y672946D01*
G01Y671113D02*
X381960Y671947D01*
X382793Y672613D01*
X383960Y672946D01*
X385126Y672613D01*
X385960Y671947D01*
X386460Y671113D01*
Y666280D01*
G01Y671113D02*
X386960Y671947D01*
X387793Y672613D01*
X388960Y672946D01*
X390127Y672613D01*
X390960Y671947D01*
X391460Y670947D01*
Y666280D01*
G01X395260Y670780D02*
X400593D01*
X400093Y671947D01*
X399260Y672613D01*
X398093Y672946D01*
X396927Y672780D01*
X395927Y672280D01*
X395260Y671113D01*
X394927Y670113D01*
Y669113D01*
X395260Y668113D01*
X396093Y667113D01*
X397093Y666447D01*
X398260Y666280D01*
X399427Y666613D01*
X400593Y667613D01*
G01X409060Y676280D02*
Y666280D01*
G01X406727Y672946D02*
X411393D01*
G01X417860Y670780D02*
X423193D01*
X422693Y671947D01*
X421860Y672613D01*
X420693Y672946D01*
X419527Y672780D01*
X418527Y672280D01*
X417860Y671113D01*
X417527Y670113D01*
Y669113D01*
X417860Y668113D01*
X418693Y667113D01*
X419693Y666447D01*
X420860Y666280D01*
X422027Y666613D01*
X423193Y667613D01*
G01X429327Y666280D02*
Y672946D01*
G01Y671613D02*
X430160Y672280D01*
X430993Y672780D01*
X432160Y672946D01*
X432993Y672780D01*
X433993Y672280D01*
G01X440793Y668113D02*
X445127D01*
G01Y671113D02*
X440793D01*
G01X451427Y667446D02*
X452593Y666613D01*
X453927Y666280D01*
X455260Y666613D01*
X456427Y667613D01*
X457260Y669113D01*
X457593Y670613D01*
Y672447D01*
X457260Y673947D01*
X456427Y675280D01*
X455427Y675947D01*
X454260Y676280D01*
X452926Y675947D01*
X451927Y675280D01*
X451260Y674280D01*
X450927Y672946D01*
X451260Y671780D01*
X452093Y670613D01*
X453093Y669946D01*
X454260Y669780D01*
X455593Y670113D01*
X456593Y670947D01*
X457593Y672447D01*
G01X461893Y668280D02*
X462893Y667113D01*
X464226Y666447D01*
X465727Y666280D01*
X467060Y666447D01*
X468393Y667280D01*
X469227Y668280D01*
X469393Y669280D01*
X469060Y670446D01*
X467893Y671280D01*
X466727Y671613D01*
X465227D01*
G01X466727D02*
X467727Y672113D01*
X468560Y672946D01*
X468893Y673947D01*
X468560Y674947D01*
X467727Y675780D01*
X466227Y676280D01*
X464727Y676113D01*
X463227Y675447D01*
G01X287760Y613280D02*
X291093D01*
Y610280D01*
X290093Y609280D01*
X288927Y608613D01*
X287260Y608280D01*
X285593Y608613D01*
X284427Y609280D01*
X283427Y610280D01*
X282760Y611447D01*
X282427Y612780D01*
Y613947D01*
X282760Y614946D01*
X283427Y616113D01*
X284427Y617113D01*
X285426Y617780D01*
X286760Y618280D01*
X287927D01*
X289260Y617947D01*
X290260Y617280D01*
G01X301060Y608280D02*
Y614946D01*
G01Y613780D02*
X300393Y614447D01*
X299393Y614780D01*
X298227Y614946D01*
X297060Y614613D01*
X296060Y613947D01*
X295393Y612947D01*
X295060Y611613D01*
X295393Y610280D01*
X296060Y609280D01*
X297060Y608613D01*
X298227Y608280D01*
X299393Y608447D01*
X300393Y608947D01*
X301060Y609613D01*
G01X306360Y604947D02*
Y614946D01*
G01Y613447D02*
X307193Y614280D01*
X308026Y614780D01*
X309360Y614946D01*
X310527Y614780D01*
X311693Y613947D01*
X312193Y612780D01*
X312360Y611613D01*
X312193Y610447D01*
X311693Y609280D01*
X310693Y608613D01*
X309360Y608280D01*
X308193Y608447D01*
X307027Y608947D01*
X306360Y609613D01*
G01X326960Y618280D02*
X329293Y608280D01*
X331960Y618280D01*
X334627Y608280D01*
X336960Y618280D01*
G01X343260Y614946D02*
Y608280D01*
G01Y617613D02*
X342927Y617780D01*
Y618113D01*
X343260Y618280D01*
X343593Y618113D01*
Y617780D01*
X343260Y617613D01*
G01X357560Y618280D02*
Y608280D01*
G01Y609780D02*
X356893Y608947D01*
X355893Y608447D01*
X354727Y608280D01*
X353393Y608613D01*
X352393Y609446D01*
X351727Y610447D01*
X351560Y611613D01*
X351727Y612780D01*
X352393Y613780D01*
X353393Y614613D01*
X354727Y614946D01*
X355893Y614780D01*
X356727Y614447D01*
X357560Y613780D01*
G01X365860Y618280D02*
Y608280D01*
G01X363527Y614946D02*
X368193D01*
G01X374327Y608280D02*
Y618280D01*
G01Y613447D02*
X375160Y614280D01*
X375993Y614780D01*
X377327Y614946D01*
X378327Y614780D01*
X379493Y614113D01*
X379993Y613113D01*
Y608280D01*
G01X386293Y610113D02*
X390627D01*
G01Y613113D02*
X386293D01*
G01X396093Y610280D02*
X397093Y609113D01*
X398426Y608447D01*
X399927Y608280D01*
X401260Y608447D01*
X402593Y609280D01*
X403427Y610280D01*
X403593Y611280D01*
X403260Y612446D01*
X402093Y613280D01*
X400927Y613613D01*
X399427D01*
G01X400927D02*
X401927Y614113D01*
X402760Y614946D01*
X403093Y615947D01*
X402760Y616947D01*
X401927Y617780D01*
X400427Y618280D01*
X398927Y618113D01*
X397427Y617447D01*
G01X411060Y618280D02*
X409726Y617947D01*
X408727Y617113D01*
X408060Y616113D01*
X407560Y614780D01*
X407393Y613280D01*
X407560Y611780D01*
X408060Y610447D01*
X408727Y609446D01*
X409726Y608613D01*
X411060Y608280D01*
X412393Y608613D01*
X413393Y609446D01*
X414060Y610447D01*
X414560Y611780D01*
X414727Y613280D01*
X414560Y614780D01*
X414060Y616113D01*
X413393Y617113D01*
X412393Y617947D01*
X411060Y618280D01*
G01X284927Y624280D02*
Y634280D01*
X292593Y624280D01*
Y634280D01*
G01X297227Y630946D02*
Y626280D01*
X297893Y625113D01*
X298893Y624447D01*
X300060Y624280D01*
X301227Y624447D01*
X302227Y625113D01*
X302893Y626280D01*
G01Y624280D02*
Y630946D01*
G01X306360Y624280D02*
Y630946D01*
G01Y629113D02*
X306860Y629947D01*
X307693Y630613D01*
X308860Y630946D01*
X310026Y630613D01*
X310860Y629947D01*
X311360Y629113D01*
Y624280D01*
G01Y629113D02*
X311860Y629947D01*
X312693Y630613D01*
X313860Y630946D01*
X315027Y630613D01*
X315860Y629947D01*
X316360Y628947D01*
Y624280D01*
G01X330460Y625613D02*
X331793Y624780D01*
X333293Y624280D01*
X334627D01*
X335960Y624780D01*
X336960Y625613D01*
X337460Y626780D01*
X337127Y627946D01*
X336293Y628947D01*
X334793Y629613D01*
X332793Y629947D01*
X331627Y630613D01*
X331127Y631780D01*
X331460Y632947D01*
X332293Y633780D01*
X333460Y634280D01*
X334627D01*
X335793Y633947D01*
X336793Y633113D01*
G01X342260Y620947D02*
Y630946D01*
G01Y629447D02*
X343093Y630280D01*
X343926Y630780D01*
X345260Y630946D01*
X346427Y630780D01*
X347593Y629947D01*
X348093Y628780D01*
X348260Y627613D01*
X348093Y626447D01*
X347593Y625280D01*
X346593Y624613D01*
X345260Y624280D01*
X344093Y624447D01*
X342927Y624947D01*
X342260Y625613D01*
G01X356560Y624280D02*
X355560Y624447D01*
X354560Y625113D01*
X353893Y626280D01*
X353560Y627613D01*
X353893Y628947D01*
X354560Y630113D01*
X355560Y630780D01*
X356560Y630946D01*
X357560Y630780D01*
X358560Y630113D01*
X359227Y628947D01*
X359393Y627613D01*
X359227Y626280D01*
X358560Y625113D01*
X357560Y624447D01*
X356560Y624280D01*
G01X365027D02*
Y634280D01*
G01X370360Y630946D02*
X365027Y627113D01*
G01X367193Y628613D02*
X370693Y624280D01*
G01X376660Y628780D02*
X381993D01*
X381493Y629947D01*
X380660Y630613D01*
X379493Y630946D01*
X378327Y630780D01*
X377327Y630280D01*
X376660Y629113D01*
X376327Y628113D01*
Y627113D01*
X376660Y626113D01*
X377493Y625113D01*
X378493Y624447D01*
X379660Y624280D01*
X380827Y624613D01*
X381993Y625613D01*
G01X387960Y625446D02*
X388793Y624780D01*
X389960Y624280D01*
X390960D01*
X391960Y624613D01*
X392627Y625113D01*
X392960Y625780D01*
X392793Y626780D01*
X392127Y627280D01*
X389126Y628280D01*
X388460Y629447D01*
X388793Y630280D01*
X389460Y630780D01*
X390460Y630946D01*
X391460Y630780D01*
X392460Y630280D01*
G01X399593Y626113D02*
X403927D01*
G01Y629113D02*
X399593D01*
G01X415060Y624280D02*
Y634280D01*
X408893Y627113D01*
X417227D01*
G01X286760Y644280D02*
X285426Y644447D01*
X284260Y645113D01*
X283260Y646113D01*
X282593Y647280D01*
X282260Y648613D01*
Y649947D01*
X282593Y651280D01*
X283260Y652447D01*
X284260Y653447D01*
X285426Y654113D01*
X286760Y654280D01*
X288093Y654113D01*
X289260Y653447D01*
X290260Y652447D01*
X290927Y651280D01*
X291260Y649947D01*
Y648613D01*
X290927Y647280D01*
X290260Y646113D01*
X289260Y645113D01*
X288093Y644447D01*
X286760Y644280D01*
G01X295227Y650946D02*
Y646280D01*
X295893Y645113D01*
X296893Y644447D01*
X298060Y644280D01*
X299227Y644447D01*
X300227Y645113D01*
X300893Y646280D01*
G01Y644280D02*
Y650946D01*
G01X309360Y654280D02*
Y644280D01*
G01X307027Y650946D02*
X311693D01*
G01X318160Y648780D02*
X323493D01*
X322993Y649947D01*
X322160Y650613D01*
X320993Y650946D01*
X319827Y650780D01*
X318827Y650280D01*
X318160Y649113D01*
X317827Y648113D01*
Y647113D01*
X318160Y646113D01*
X318993Y645113D01*
X319993Y644447D01*
X321160Y644280D01*
X322327Y644613D01*
X323493Y645613D01*
G01X329627Y644280D02*
Y650946D01*
G01Y649613D02*
X330460Y650280D01*
X331293Y650780D01*
X332460Y650946D01*
X333293Y650780D01*
X334293Y650280D01*
G01X350893Y644280D02*
Y654280D01*
X354227D01*
X355560Y653780D01*
X356560Y653113D01*
X357393Y652113D01*
X358060Y650946D01*
X358227Y649280D01*
X358060Y647613D01*
X357393Y646447D01*
X356560Y645446D01*
X355560Y644780D01*
X354227Y644280D01*
X350893D01*
G01X365860Y650946D02*
Y644280D01*
G01Y653613D02*
X365527Y653780D01*
Y654113D01*
X365860Y654280D01*
X366193Y654113D01*
Y653780D01*
X365860Y653613D01*
G01X380160Y644280D02*
Y650946D01*
G01Y649780D02*
X379493Y650447D01*
X378493Y650780D01*
X377327Y650946D01*
X376160Y650613D01*
X375160Y649947D01*
X374493Y648947D01*
X374160Y647613D01*
X374493Y646280D01*
X375160Y645280D01*
X376160Y644613D01*
X377327Y644280D01*
X378493Y644447D01*
X379493Y644947D01*
X380160Y645613D01*
G01X383460Y644280D02*
Y650946D01*
G01Y649113D02*
X383960Y649947D01*
X384793Y650613D01*
X385960Y650946D01*
X387126Y650613D01*
X387960Y649947D01*
X388460Y649113D01*
Y644280D01*
G01Y649113D02*
X388960Y649947D01*
X389793Y650613D01*
X390960Y650946D01*
X392127Y650613D01*
X392960Y649947D01*
X393460Y648947D01*
Y644280D01*
G01X397260Y648780D02*
X402593D01*
X402093Y649947D01*
X401260Y650613D01*
X400093Y650946D01*
X398927Y650780D01*
X397927Y650280D01*
X397260Y649113D01*
X396927Y648113D01*
Y647113D01*
X397260Y646113D01*
X398093Y645113D01*
X399093Y644447D01*
X400260Y644280D01*
X401427Y644613D01*
X402593Y645613D01*
G01X411060Y654280D02*
Y644280D01*
G01X408727Y650946D02*
X413393D01*
G01X419860Y648780D02*
X425193D01*
X424693Y649947D01*
X423860Y650613D01*
X422693Y650946D01*
X421527Y650780D01*
X420527Y650280D01*
X419860Y649113D01*
X419527Y648113D01*
Y647113D01*
X419860Y646113D01*
X420693Y645113D01*
X421693Y644447D01*
X422860Y644280D01*
X424027Y644613D01*
X425193Y645613D01*
G01X431327Y644280D02*
Y650946D01*
G01Y649613D02*
X432160Y650280D01*
X432993Y650780D01*
X434160Y650946D01*
X434993Y650780D01*
X435993Y650280D01*
G01X442793Y646113D02*
X447127D01*
G01Y649113D02*
X442793D01*
G01X456260Y644280D02*
Y654280D01*
X454260Y652280D01*
G01Y644280D02*
X458260D01*
G01X467560Y654280D02*
X466226Y653947D01*
X465227Y653113D01*
X464560Y652113D01*
X464060Y650780D01*
X463893Y649280D01*
X464060Y647780D01*
X464560Y646447D01*
X465227Y645446D01*
X466226Y644613D01*
X467560Y644280D01*
X468893Y644613D01*
X469893Y645446D01*
X470560Y646447D01*
X471060Y647780D01*
X471227Y649280D01*
X471060Y650780D01*
X470560Y652113D01*
X469893Y653113D01*
X468893Y653947D01*
X467560Y654280D01*
G01X475193Y646280D02*
X476193Y645113D01*
X477526Y644447D01*
X479027Y644280D01*
X480360Y644447D01*
X481693Y645280D01*
X482527Y646280D01*
X482693Y647280D01*
X482360Y648446D01*
X481193Y649280D01*
X480027Y649613D01*
X478527D01*
G01X480027D02*
X481027Y650113D01*
X481860Y650946D01*
X482193Y651947D01*
X481860Y652947D01*
X481027Y653780D01*
X479527Y654280D01*
X478027Y654113D01*
X476527Y653447D01*
G54D12*
G01X595558Y122380D02*
Y130365D01*
X599351D01*
G01X597954Y126506D02*
X595558D01*
G01X605439Y122380D02*
X604841Y122513D01*
X604242Y123045D01*
X603842Y123977D01*
X603643Y125042D01*
X603842Y126106D01*
X604242Y127038D01*
X604841Y127570D01*
X605439Y127703D01*
X606038Y127570D01*
X606637Y127038D01*
X607036Y126106D01*
X607136Y125042D01*
X607036Y123977D01*
X606637Y123045D01*
X606038Y122513D01*
X605439Y122380D01*
G01X612027D02*
Y127703D01*
G01Y126639D02*
X612526Y127171D01*
X613025Y127570D01*
X613724Y127703D01*
X614223Y127570D01*
X614822Y127171D01*
G01X627897Y125973D02*
X631091D01*
X630792Y126905D01*
X630293Y127437D01*
X629594Y127703D01*
X628895Y127570D01*
X628296Y127171D01*
X627897Y126239D01*
X627698Y125441D01*
Y124642D01*
X627897Y123844D01*
X628396Y123045D01*
X628995Y122513D01*
X629694Y122380D01*
X630393Y122646D01*
X631091Y123444D01*
G01X635882Y127703D02*
X638877Y122380D01*
G01Y127703D02*
X635882Y122380D01*
G01X647161D02*
Y127703D01*
G01Y126772D02*
X646762Y127304D01*
X646163Y127570D01*
X645464Y127703D01*
X644766Y127437D01*
X644167Y126905D01*
X643767Y126106D01*
X643568Y125042D01*
X643767Y123977D01*
X644167Y123178D01*
X644766Y122646D01*
X645464Y122380D01*
X646163Y122513D01*
X646762Y122912D01*
X647161Y123444D01*
G01X650355Y122380D02*
Y127703D01*
G01Y126239D02*
X650654Y126905D01*
X651154Y127437D01*
X651852Y127703D01*
X652551Y127437D01*
X653050Y126905D01*
X653349Y126239D01*
Y122380D01*
G01Y126239D02*
X653649Y126905D01*
X654148Y127437D01*
X654847Y127703D01*
X655545Y127437D01*
X656045Y126905D01*
X656344Y126106D01*
Y122380D01*
G01X659538Y119718D02*
Y127703D01*
G01Y126506D02*
X660037Y127171D01*
X660536Y127570D01*
X661334Y127703D01*
X662033Y127570D01*
X662732Y126905D01*
X663031Y125973D01*
X663131Y125042D01*
X663031Y124110D01*
X662732Y123178D01*
X662133Y122646D01*
X661334Y122380D01*
X660636Y122513D01*
X659937Y122912D01*
X659538Y123444D01*
G01X669319Y122380D02*
Y130365D01*
G01X675807Y125973D02*
X679001D01*
X678702Y126905D01*
X678203Y127437D01*
X677504Y127703D01*
X676805Y127570D01*
X676206Y127171D01*
X675807Y126239D01*
X675608Y125441D01*
Y124642D01*
X675807Y123844D01*
X676306Y123045D01*
X676905Y122513D01*
X677604Y122380D01*
X678303Y122646D01*
X679001Y123444D01*
G01X685289Y122114D02*
X685090Y122247D01*
Y122513D01*
X685289Y122646D01*
X685489Y122513D01*
Y122247D01*
X685289Y122114D01*
G01Y125707D02*
X685090Y125840D01*
Y126106D01*
X685289Y126239D01*
X685489Y126106D01*
Y125840D01*
X685289Y125707D01*
G01X699163Y122380D02*
Y130365D01*
G01X703356D02*
Y122380D01*
G01Y126372D02*
X699163D01*
G01X709244Y122380D02*
X708646Y122513D01*
X708047Y123045D01*
X707647Y123977D01*
X707448Y125042D01*
X707647Y126106D01*
X708047Y127038D01*
X708646Y127570D01*
X709244Y127703D01*
X709843Y127570D01*
X710442Y127038D01*
X710841Y126106D01*
X710941Y125042D01*
X710841Y123977D01*
X710442Y123045D01*
X709843Y122513D01*
X709244Y122380D01*
G01X717229D02*
Y130365D01*
G01X723717Y125973D02*
X726911D01*
X726612Y126905D01*
X726113Y127437D01*
X725414Y127703D01*
X724715Y127570D01*
X724116Y127171D01*
X723717Y126239D01*
X723518Y125441D01*
Y124642D01*
X723717Y123844D01*
X724216Y123045D01*
X724815Y122513D01*
X725514Y122380D01*
X726213Y122646D01*
X726911Y123444D01*
G01X738989Y122380D02*
Y130365D01*
X740985D01*
X741783Y129966D01*
X742382Y129433D01*
X742881Y128635D01*
X743281Y127703D01*
X743380Y126372D01*
X743281Y125042D01*
X742881Y124110D01*
X742382Y123311D01*
X741783Y122779D01*
X740985Y122380D01*
X738989D01*
G01X749169Y127703D02*
Y122380D01*
G01Y129833D02*
X748970Y129966D01*
Y130232D01*
X749169Y130365D01*
X749369Y130232D01*
Y129966D01*
X749169Y129833D01*
G01X758951Y122380D02*
Y127703D01*
G01Y126772D02*
X758552Y127304D01*
X757953Y127570D01*
X757254Y127703D01*
X756556Y127437D01*
X755957Y126905D01*
X755557Y126106D01*
X755358Y125042D01*
X755557Y123977D01*
X755957Y123178D01*
X756556Y122646D01*
X757254Y122380D01*
X757953Y122513D01*
X758552Y122912D01*
X758951Y123444D01*
G01X765139Y122114D02*
X764940Y122247D01*
Y122513D01*
X765139Y122646D01*
X765339Y122513D01*
Y122247D01*
X765139Y122114D01*
G01X770929Y123977D02*
X771527Y123045D01*
X772326Y122513D01*
X773224Y122380D01*
X774023Y122513D01*
X774821Y123178D01*
X775320Y123977D01*
X775420Y124775D01*
X775221Y125707D01*
X774522Y126372D01*
X773823Y126639D01*
X772925D01*
G01X773823D02*
X774422Y127038D01*
X774921Y127703D01*
X775121Y128502D01*
X774921Y129300D01*
X774422Y129966D01*
X773524Y130365D01*
X772625Y130232D01*
X771727Y129699D01*
G01X781109Y122114D02*
X780910Y122247D01*
Y122513D01*
X781109Y122646D01*
X781309Y122513D01*
Y122247D01*
X781109Y122114D01*
G01X789094Y122380D02*
Y130365D01*
X787897Y128768D01*
G01Y122380D02*
X790292D01*
G01X797079D02*
X797778Y122513D01*
X798577Y122912D01*
X799076Y123577D01*
X799275Y124509D01*
X799076Y125441D01*
X798477Y126239D01*
X797579Y126639D01*
X796580D01*
X795981Y126905D01*
X795482Y127570D01*
X795283Y128502D01*
X795582Y129433D01*
X796281Y130099D01*
X797079Y130365D01*
X797878Y130099D01*
X798577Y129433D01*
X798876Y128502D01*
X798676Y127570D01*
X798178Y126905D01*
X797579Y126639D01*
X796580D01*
X795682Y126239D01*
X795083Y125441D01*
X794884Y124509D01*
X795083Y123577D01*
X795582Y122912D01*
X796381Y122513D01*
X797079Y122380D01*
G01X802070D02*
Y127703D01*
G01Y126239D02*
X802369Y126905D01*
X802869Y127437D01*
X803567Y127703D01*
X804266Y127437D01*
X804765Y126905D01*
X805064Y126239D01*
Y122380D01*
G01Y126239D02*
X805364Y126905D01*
X805863Y127437D01*
X806562Y127703D01*
X807260Y127437D01*
X807760Y126905D01*
X808059Y126106D01*
Y122380D01*
G01X810055D02*
Y127703D01*
G01Y126239D02*
X810354Y126905D01*
X810854Y127437D01*
X811552Y127703D01*
X812251Y127437D01*
X812750Y126905D01*
X813049Y126239D01*
Y122380D01*
G01Y126239D02*
X813349Y126905D01*
X813848Y127437D01*
X814547Y127703D01*
X815245Y127437D01*
X815745Y126905D01*
X816044Y126106D01*
Y122380D01*
G01X829019Y127703D02*
Y122380D01*
G01Y129833D02*
X828820Y129966D01*
Y130232D01*
X829019Y130365D01*
X829219Y130232D01*
Y129966D01*
X829019Y129833D01*
G01X835507Y123311D02*
X836006Y122779D01*
X836705Y122380D01*
X837304D01*
X837903Y122646D01*
X838302Y123045D01*
X838502Y123577D01*
X838402Y124376D01*
X838003Y124775D01*
X836206Y125574D01*
X835807Y126506D01*
X836006Y127171D01*
X836406Y127570D01*
X837004Y127703D01*
X837603Y127570D01*
X838202Y127171D01*
G01X849980Y122380D02*
Y127703D01*
G01Y126239D02*
X850279Y126905D01*
X850779Y127437D01*
X851477Y127703D01*
X852176Y127437D01*
X852675Y126905D01*
X852974Y126239D01*
Y122380D01*
G01Y126239D02*
X853274Y126905D01*
X853773Y127437D01*
X854472Y127703D01*
X855170Y127437D01*
X855670Y126905D01*
X855969Y126106D01*
Y122380D01*
G01X862756D02*
Y127703D01*
G01Y126772D02*
X862357Y127304D01*
X861758Y127570D01*
X861059Y127703D01*
X860361Y127437D01*
X859762Y126905D01*
X859362Y126106D01*
X859163Y125042D01*
X859362Y123977D01*
X859762Y123178D01*
X860361Y122646D01*
X861059Y122380D01*
X861758Y122513D01*
X862357Y122912D01*
X862756Y123444D01*
G01X867547Y122380D02*
Y127703D01*
G01Y126639D02*
X868046Y127171D01*
X868545Y127570D01*
X869244Y127703D01*
X869743Y127570D01*
X870342Y127171D01*
G01X875233Y122380D02*
Y130365D01*
G01X878427Y127703D02*
X875233Y124642D01*
G01X876530Y125840D02*
X878626Y122380D01*
G01X883417Y125973D02*
X886611D01*
X886312Y126905D01*
X885813Y127437D01*
X885114Y127703D01*
X884415Y127570D01*
X883816Y127171D01*
X883417Y126239D01*
X883218Y125441D01*
Y124642D01*
X883417Y123844D01*
X883916Y123045D01*
X884515Y122513D01*
X885214Y122380D01*
X885913Y122646D01*
X886611Y123444D01*
G01X894696Y130365D02*
Y122380D01*
G01Y123577D02*
X894297Y122912D01*
X893698Y122513D01*
X892999Y122380D01*
X892201Y122646D01*
X891602Y123311D01*
X891203Y124110D01*
X891103Y125042D01*
X891203Y125973D01*
X891602Y126772D01*
X892201Y127437D01*
X892999Y127703D01*
X893698Y127570D01*
X894197Y127304D01*
X894696Y126772D01*
G01X908869Y127703D02*
Y122380D01*
G01Y129833D02*
X908670Y129966D01*
Y130232D01*
X908869Y130365D01*
X909069Y130232D01*
Y129966D01*
X908869Y129833D01*
G01X915158Y122380D02*
Y127703D01*
G01Y126372D02*
X915557Y127038D01*
X916156Y127570D01*
X916954Y127703D01*
X917653Y127570D01*
X918252Y127038D01*
X918551Y126106D01*
Y122380D01*
G01X929830D02*
Y127703D01*
G01Y126239D02*
X930129Y126905D01*
X930629Y127437D01*
X931327Y127703D01*
X932026Y127437D01*
X932525Y126905D01*
X932824Y126239D01*
Y122380D01*
G01Y126239D02*
X933124Y126905D01*
X933623Y127437D01*
X934322Y127703D01*
X935020Y127437D01*
X935520Y126905D01*
X935819Y126106D01*
Y122380D01*
G01X939312Y125973D02*
X942506D01*
X942207Y126905D01*
X941708Y127437D01*
X941009Y127703D01*
X940310Y127570D01*
X939711Y127171D01*
X939312Y126239D01*
X939113Y125441D01*
Y124642D01*
X939312Y123844D01*
X939811Y123045D01*
X940410Y122513D01*
X941109Y122380D01*
X941808Y122646D01*
X942506Y123444D01*
G01X950391Y127038D02*
X949693Y127570D01*
X949094Y127703D01*
X948295Y127437D01*
X947696Y126905D01*
X947297Y125973D01*
X947197Y125042D01*
X947297Y124110D01*
X947696Y123311D01*
X948295Y122646D01*
X949094Y122380D01*
X949793Y122646D01*
X950391Y123178D01*
G01X955083Y122380D02*
Y130365D01*
G01Y126506D02*
X955582Y127171D01*
X956081Y127570D01*
X956879Y127703D01*
X957478Y127570D01*
X958177Y127038D01*
X958476Y126239D01*
Y122380D01*
G01X966561D02*
Y127703D01*
G01Y126772D02*
X966162Y127304D01*
X965563Y127570D01*
X964864Y127703D01*
X964166Y127437D01*
X963567Y126905D01*
X963167Y126106D01*
X962968Y125042D01*
X963167Y123977D01*
X963567Y123178D01*
X964166Y122646D01*
X964864Y122380D01*
X965563Y122513D01*
X966162Y122912D01*
X966561Y123444D01*
G01X971053Y122380D02*
Y127703D01*
G01Y126372D02*
X971452Y127038D01*
X972051Y127570D01*
X972849Y127703D01*
X973548Y127570D01*
X974147Y127038D01*
X974446Y126106D01*
Y122380D01*
G01X980734Y127703D02*
Y122380D01*
G01Y129833D02*
X980535Y129966D01*
Y130232D01*
X980734Y130365D01*
X980934Y130232D01*
Y129966D01*
X980734Y129833D01*
G01X990316Y127038D02*
X989618Y127570D01*
X989019Y127703D01*
X988220Y127437D01*
X987621Y126905D01*
X987222Y125973D01*
X987122Y125042D01*
X987222Y124110D01*
X987621Y123311D01*
X988220Y122646D01*
X989019Y122380D01*
X989718Y122646D01*
X990316Y123178D01*
G01X998501Y122380D02*
Y127703D01*
G01Y126772D02*
X998102Y127304D01*
X997503Y127570D01*
X996804Y127703D01*
X996106Y127437D01*
X995507Y126905D01*
X995107Y126106D01*
X994908Y125042D01*
X995107Y123977D01*
X995507Y123178D01*
X996106Y122646D01*
X996804Y122380D01*
X997503Y122513D01*
X998102Y122912D01*
X998501Y123444D01*
G01X1004689Y122380D02*
Y130365D01*
G01X1022456D02*
Y122380D01*
G01Y123577D02*
X1022057Y122912D01*
X1021458Y122513D01*
X1020759Y122380D01*
X1019961Y122646D01*
X1019362Y123311D01*
X1018963Y124110D01*
X1018863Y125042D01*
X1018963Y125973D01*
X1019362Y126772D01*
X1019961Y127437D01*
X1020759Y127703D01*
X1021458Y127570D01*
X1021957Y127304D01*
X1022456Y126772D01*
G01X1027247Y122380D02*
Y127703D01*
G01Y126639D02*
X1027746Y127171D01*
X1028245Y127570D01*
X1028944Y127703D01*
X1029443Y127570D01*
X1030042Y127171D01*
G01X1038426Y122380D02*
Y127703D01*
G01Y126772D02*
X1038027Y127304D01*
X1037428Y127570D01*
X1036729Y127703D01*
X1036031Y127437D01*
X1035432Y126905D01*
X1035032Y126106D01*
X1034833Y125042D01*
X1035032Y123977D01*
X1035432Y123178D01*
X1036031Y122646D01*
X1036729Y122380D01*
X1037428Y122513D01*
X1038027Y122912D01*
X1038426Y123444D01*
G01X1042119Y127703D02*
X1043317Y122380D01*
X1044614Y127703D01*
X1045912Y122380D01*
X1047110Y127703D01*
G01X1052599D02*
Y122380D01*
G01Y129833D02*
X1052400Y129966D01*
Y130232D01*
X1052599Y130365D01*
X1052799Y130232D01*
Y129966D01*
X1052599Y129833D01*
G01X1058888Y122380D02*
Y127703D01*
G01Y126372D02*
X1059287Y127038D01*
X1059886Y127570D01*
X1060684Y127703D01*
X1061383Y127570D01*
X1061982Y127038D01*
X1062281Y126106D01*
Y122380D01*
G01X1067172Y120384D02*
X1067871Y119851D01*
X1068669Y119718D01*
X1069368Y119851D01*
X1069967Y120517D01*
X1070366Y121448D01*
Y127703D01*
G01Y126639D02*
X1069967Y127171D01*
X1069368Y127570D01*
X1068669Y127703D01*
X1067871Y127437D01*
X1067372Y126905D01*
X1066972Y125973D01*
X1066773Y125042D01*
X1066873Y124243D01*
X1067272Y123311D01*
X1067871Y122646D01*
X1068669Y122380D01*
X1069268Y122513D01*
X1069967Y123045D01*
X1070366Y123577D01*
G01X1086336Y122380D02*
Y127703D01*
G01Y126772D02*
X1085937Y127304D01*
X1085338Y127570D01*
X1084639Y127703D01*
X1083941Y127437D01*
X1083342Y126905D01*
X1082942Y126106D01*
X1082743Y125042D01*
X1082942Y123977D01*
X1083342Y123178D01*
X1083941Y122646D01*
X1084639Y122380D01*
X1085338Y122513D01*
X1085937Y122912D01*
X1086336Y123444D01*
G01X1090828Y122380D02*
Y127703D01*
G01Y126372D02*
X1091227Y127038D01*
X1091826Y127570D01*
X1092624Y127703D01*
X1093323Y127570D01*
X1093922Y127038D01*
X1094221Y126106D01*
Y122380D01*
G01X1102306Y130365D02*
Y122380D01*
G01Y123577D02*
X1101907Y122912D01*
X1101308Y122513D01*
X1100609Y122380D01*
X1099811Y122646D01*
X1099212Y123311D01*
X1098813Y124110D01*
X1098713Y125042D01*
X1098813Y125973D01*
X1099212Y126772D01*
X1099811Y127437D01*
X1100609Y127703D01*
X1101308Y127570D01*
X1101807Y127304D01*
X1102306Y126772D01*
G01X1114783Y122380D02*
Y130365D01*
G01Y126506D02*
X1115282Y127171D01*
X1115781Y127570D01*
X1116579Y127703D01*
X1117178Y127570D01*
X1117877Y127038D01*
X1118176Y126239D01*
Y122380D01*
G01X1124464D02*
X1123866Y122513D01*
X1123267Y123045D01*
X1122867Y123977D01*
X1122668Y125042D01*
X1122867Y126106D01*
X1123267Y127038D01*
X1123866Y127570D01*
X1124464Y127703D01*
X1125063Y127570D01*
X1125662Y127038D01*
X1126061Y126106D01*
X1126161Y125042D01*
X1126061Y123977D01*
X1125662Y123045D01*
X1125063Y122513D01*
X1124464Y122380D01*
G01X1132449D02*
Y130365D01*
G01X1138937Y125973D02*
X1142131D01*
X1141832Y126905D01*
X1141333Y127437D01*
X1140634Y127703D01*
X1139935Y127570D01*
X1139336Y127171D01*
X1138937Y126239D01*
X1138738Y125441D01*
Y124642D01*
X1138937Y123844D01*
X1139436Y123045D01*
X1140035Y122513D01*
X1140734Y122380D01*
X1141433Y122646D01*
X1142131Y123444D01*
G01X1154209Y122380D02*
Y130365D01*
X1156205D01*
X1157003Y129966D01*
X1157602Y129433D01*
X1158101Y128635D01*
X1158501Y127703D01*
X1158600Y126372D01*
X1158501Y125042D01*
X1158101Y124110D01*
X1157602Y123311D01*
X1157003Y122779D01*
X1156205Y122380D01*
X1154209D01*
G01X1164389Y127703D02*
Y122380D01*
G01Y129833D02*
X1164190Y129966D01*
Y130232D01*
X1164389Y130365D01*
X1164589Y130232D01*
Y129966D01*
X1164389Y129833D01*
G01X1174171Y122380D02*
Y127703D01*
G01Y126772D02*
X1173772Y127304D01*
X1173173Y127570D01*
X1172474Y127703D01*
X1171776Y127437D01*
X1171177Y126905D01*
X1170777Y126106D01*
X1170578Y125042D01*
X1170777Y123977D01*
X1171177Y123178D01*
X1171776Y122646D01*
X1172474Y122380D01*
X1173173Y122513D01*
X1173772Y122912D01*
X1174171Y123444D01*
G01X1180359Y122114D02*
X1180160Y122247D01*
Y122513D01*
X1180359Y122646D01*
X1180559Y122513D01*
Y122247D01*
X1180359Y122114D01*
G01X1196329Y122380D02*
Y130365D01*
X1195132Y128768D01*
G01Y122380D02*
X1197527D01*
G01X1202418Y129034D02*
X1203017Y129833D01*
X1203716Y130232D01*
X1204514Y130365D01*
X1205512Y130099D01*
X1206211Y129433D01*
X1206411Y128635D01*
X1206311Y127836D01*
X1205911Y127171D01*
X1203915Y125840D01*
X1203017Y124909D01*
X1202418Y123577D01*
X1202218Y122380D01*
X1206411D01*
G01X1210403Y125707D02*
X1211102Y126639D01*
X1211701Y127171D01*
X1212499Y127437D01*
X1213198Y127171D01*
X1213697Y126639D01*
X1214096Y125840D01*
X1214196Y124909D01*
X1214096Y124110D01*
X1213697Y123311D01*
X1213098Y122646D01*
X1212399Y122380D01*
X1211601Y122646D01*
X1210902Y123444D01*
X1210503Y124642D01*
X1210403Y125973D01*
X1210603Y127703D01*
X1210902Y128635D01*
X1211401Y129566D01*
X1212100Y130232D01*
X1212799Y130365D01*
X1213497Y130099D01*
X1213996Y129433D01*
G01X1217290Y122380D02*
Y127703D01*
G01Y126239D02*
X1217589Y126905D01*
X1218089Y127437D01*
X1218787Y127703D01*
X1219486Y127437D01*
X1219985Y126905D01*
X1220284Y126239D01*
Y122380D01*
G01Y126239D02*
X1220584Y126905D01*
X1221083Y127437D01*
X1221782Y127703D01*
X1222480Y127437D01*
X1222980Y126905D01*
X1223279Y126106D01*
Y122380D01*
G01X1228269Y127703D02*
Y122380D01*
G01Y129833D02*
X1228070Y129966D01*
Y130232D01*
X1228269Y130365D01*
X1228469Y130232D01*
Y129966D01*
X1228269Y129833D01*
G01X1236254Y122380D02*
Y130365D01*
G01X1252224Y127703D02*
Y122380D01*
G01Y129833D02*
X1252025Y129966D01*
Y130232D01*
X1252224Y130365D01*
X1252424Y130232D01*
Y129966D01*
X1252224Y129833D01*
G01X1258712Y123311D02*
X1259211Y122779D01*
X1259910Y122380D01*
X1260509D01*
X1261108Y122646D01*
X1261507Y123045D01*
X1261707Y123577D01*
X1261607Y124376D01*
X1261208Y124775D01*
X1259411Y125574D01*
X1259012Y126506D01*
X1259211Y127171D01*
X1259611Y127570D01*
X1260209Y127703D01*
X1260808Y127570D01*
X1261407Y127171D01*
G01X1273185Y122380D02*
Y127703D01*
G01Y126239D02*
X1273484Y126905D01*
X1273984Y127437D01*
X1274682Y127703D01*
X1275381Y127437D01*
X1275880Y126905D01*
X1276179Y126239D01*
Y122380D01*
G01Y126239D02*
X1276479Y126905D01*
X1276978Y127437D01*
X1277677Y127703D01*
X1278375Y127437D01*
X1278875Y126905D01*
X1279174Y126106D01*
Y122380D01*
G01X1285961D02*
Y127703D01*
G01Y126772D02*
X1285562Y127304D01*
X1284963Y127570D01*
X1284264Y127703D01*
X1283566Y127437D01*
X1282967Y126905D01*
X1282567Y126106D01*
X1282368Y125042D01*
X1282567Y123977D01*
X1282967Y123178D01*
X1283566Y122646D01*
X1284264Y122380D01*
X1284963Y122513D01*
X1285562Y122912D01*
X1285961Y123444D01*
G01X1290752Y122380D02*
Y127703D01*
G01Y126639D02*
X1291251Y127171D01*
X1291750Y127570D01*
X1292449Y127703D01*
X1292948Y127570D01*
X1293547Y127171D01*
G01X1298438Y122380D02*
Y130365D01*
G01X1301632Y127703D02*
X1298438Y124642D01*
G01X1299735Y125840D02*
X1301831Y122380D01*
G01X1306622Y125973D02*
X1309816D01*
X1309517Y126905D01*
X1309018Y127437D01*
X1308319Y127703D01*
X1307620Y127570D01*
X1307021Y127171D01*
X1306622Y126239D01*
X1306423Y125441D01*
Y124642D01*
X1306622Y123844D01*
X1307121Y123045D01*
X1307720Y122513D01*
X1308419Y122380D01*
X1309118Y122646D01*
X1309816Y123444D01*
G01X1317901Y130365D02*
Y122380D01*
G01Y123577D02*
X1317502Y122912D01*
X1316903Y122513D01*
X1316204Y122380D01*
X1315406Y122646D01*
X1314807Y123311D01*
X1314408Y124110D01*
X1314308Y125042D01*
X1314408Y125973D01*
X1314807Y126772D01*
X1315406Y127437D01*
X1316204Y127703D01*
X1316903Y127570D01*
X1317402Y127304D01*
X1317901Y126772D01*
G01X1332074Y127703D02*
Y122380D01*
G01Y129833D02*
X1331875Y129966D01*
Y130232D01*
X1332074Y130365D01*
X1332274Y130232D01*
Y129966D01*
X1332074Y129833D01*
G01X1338363Y122380D02*
Y127703D01*
G01Y126372D02*
X1338762Y127038D01*
X1339361Y127570D01*
X1340159Y127703D01*
X1340858Y127570D01*
X1341457Y127038D01*
X1341756Y126106D01*
Y122380D01*
G01X1356628Y126372D02*
X1358625D01*
Y123977D01*
X1358026Y123178D01*
X1357327Y122646D01*
X1356329Y122380D01*
X1355331Y122646D01*
X1354632Y123178D01*
X1354033Y123977D01*
X1353634Y124909D01*
X1353434Y125973D01*
Y126905D01*
X1353634Y127703D01*
X1354033Y128635D01*
X1354632Y129433D01*
X1355231Y129966D01*
X1356029Y130365D01*
X1356728D01*
X1357527Y130099D01*
X1358126Y129566D01*
G01X1362517Y125973D02*
X1365711D01*
X1365412Y126905D01*
X1364913Y127437D01*
X1364214Y127703D01*
X1363515Y127570D01*
X1362916Y127171D01*
X1362517Y126239D01*
X1362318Y125441D01*
Y124642D01*
X1362517Y123844D01*
X1363016Y123045D01*
X1363615Y122513D01*
X1364314Y122380D01*
X1365013Y122646D01*
X1365711Y123444D01*
G01X1370602Y122380D02*
Y127703D01*
G01Y126639D02*
X1371101Y127171D01*
X1371600Y127570D01*
X1372299Y127703D01*
X1372798Y127570D01*
X1373397Y127171D01*
G01X1378188Y122380D02*
Y130365D01*
G01Y126372D02*
X1378687Y127171D01*
X1379286Y127570D01*
X1379885Y127703D01*
X1380783Y127437D01*
X1381382Y126905D01*
X1381781Y125973D01*
Y124909D01*
X1381581Y123844D01*
X1381182Y123045D01*
X1380484Y122513D01*
X1379885Y122380D01*
X1379286Y122513D01*
X1378687Y122912D01*
X1378188Y123577D01*
G01X1386472Y125973D02*
X1389666D01*
X1389367Y126905D01*
X1388868Y127437D01*
X1388169Y127703D01*
X1387470Y127570D01*
X1386871Y127171D01*
X1386472Y126239D01*
X1386273Y125441D01*
Y124642D01*
X1386472Y123844D01*
X1386971Y123045D01*
X1387570Y122513D01*
X1388269Y122380D01*
X1388968Y122646D01*
X1389666Y123444D01*
G01X1394557Y122380D02*
Y127703D01*
G01Y126639D02*
X1395056Y127171D01*
X1395555Y127570D01*
X1396254Y127703D01*
X1396753Y127570D01*
X1397352Y127171D01*
G01X1411326Y122380D02*
Y129167D01*
X1411525Y129833D01*
X1411924Y130232D01*
X1412523Y130365D01*
X1413122Y130099D01*
X1413422Y129433D01*
G01X1412224Y127171D02*
X1410228D01*
G01X1419909Y127703D02*
Y122380D01*
G01Y129833D02*
X1419710Y129966D01*
Y130232D01*
X1419909Y130365D01*
X1420109Y130232D01*
Y129966D01*
X1419909Y129833D01*
G01X1427894Y122380D02*
Y130365D01*
G01X1434382Y125973D02*
X1437576D01*
X1437277Y126905D01*
X1436778Y127437D01*
X1436079Y127703D01*
X1435380Y127570D01*
X1434781Y127171D01*
X1434382Y126239D01*
X1434183Y125441D01*
Y124642D01*
X1434382Y123844D01*
X1434881Y123045D01*
X1435480Y122513D01*
X1436179Y122380D01*
X1436878Y122646D01*
X1437576Y123444D01*
G01X1443864Y122114D02*
X1443665Y122247D01*
Y122513D01*
X1443864Y122646D01*
X1444064Y122513D01*
Y122247D01*
X1443864Y122114D01*
G01X595757Y142165D02*
X598152D01*
G01X596954D02*
Y134180D01*
G01X595757D02*
X598152D01*
G01X604341D02*
Y140967D01*
X604540Y141633D01*
X604939Y142032D01*
X605538Y142165D01*
X606137Y141899D01*
X606437Y141233D01*
G01X605239Y138971D02*
X603243D01*
G01X620909Y139503D02*
Y134180D01*
G01Y141633D02*
X620710Y141766D01*
Y142032D01*
X620909Y142165D01*
X621109Y142032D01*
Y141766D01*
X620909Y141633D01*
G01X627397Y135111D02*
X627896Y134579D01*
X628595Y134180D01*
X629194D01*
X629793Y134446D01*
X630192Y134845D01*
X630392Y135377D01*
X630292Y136176D01*
X629893Y136575D01*
X628096Y137374D01*
X627697Y138306D01*
X627896Y138971D01*
X628296Y139370D01*
X628894Y139503D01*
X629493Y139370D01*
X630092Y138971D01*
G01X643467Y132184D02*
X644166Y131651D01*
X644964Y131518D01*
X645663Y131651D01*
X646262Y132317D01*
X646661Y133248D01*
Y139503D01*
G01Y138439D02*
X646262Y138971D01*
X645663Y139370D01*
X644964Y139503D01*
X644166Y139237D01*
X643667Y138705D01*
X643267Y137773D01*
X643068Y136842D01*
X643168Y136043D01*
X643567Y135111D01*
X644166Y134446D01*
X644964Y134180D01*
X645563Y134313D01*
X646262Y134845D01*
X646661Y135377D01*
G01X651452Y134180D02*
Y139503D01*
G01Y138439D02*
X651951Y138971D01*
X652450Y139370D01*
X653149Y139503D01*
X653648Y139370D01*
X654247Y138971D01*
G01X659337Y137773D02*
X662531D01*
X662232Y138705D01*
X661733Y139237D01*
X661034Y139503D01*
X660335Y139370D01*
X659736Y138971D01*
X659337Y138039D01*
X659138Y137241D01*
Y136442D01*
X659337Y135644D01*
X659836Y134845D01*
X660435Y134313D01*
X661134Y134180D01*
X661833Y134446D01*
X662531Y135244D01*
G01X670616Y134180D02*
Y139503D01*
G01Y138572D02*
X670217Y139104D01*
X669618Y139370D01*
X668919Y139503D01*
X668221Y139237D01*
X667622Y138705D01*
X667222Y137906D01*
X667023Y136842D01*
X667222Y135777D01*
X667622Y134978D01*
X668221Y134446D01*
X668919Y134180D01*
X669618Y134313D01*
X670217Y134712D01*
X670616Y135244D01*
G01X676804Y142165D02*
Y134180D01*
G01X675407Y139503D02*
X678202D01*
G01X683292Y137773D02*
X686486D01*
X686187Y138705D01*
X685688Y139237D01*
X684989Y139503D01*
X684290Y139370D01*
X683691Y138971D01*
X683292Y138039D01*
X683093Y137241D01*
Y136442D01*
X683292Y135644D01*
X683791Y134845D01*
X684390Y134313D01*
X685089Y134180D01*
X685788Y134446D01*
X686486Y135244D01*
G01X691377Y134180D02*
Y139503D01*
G01Y138439D02*
X691876Y138971D01*
X692375Y139370D01*
X693074Y139503D01*
X693573Y139370D01*
X694172Y138971D01*
G01X708744Y142165D02*
Y134180D01*
G01X707347Y139503D02*
X710142D01*
G01X715033Y134180D02*
Y142165D01*
G01Y138306D02*
X715532Y138971D01*
X716031Y139370D01*
X716829Y139503D01*
X717428Y139370D01*
X718127Y138838D01*
X718426Y138039D01*
Y134180D01*
G01X726511D02*
Y139503D01*
G01Y138572D02*
X726112Y139104D01*
X725513Y139370D01*
X724814Y139503D01*
X724116Y139237D01*
X723517Y138705D01*
X723117Y137906D01*
X722918Y136842D01*
X723117Y135777D01*
X723517Y134978D01*
X724116Y134446D01*
X724814Y134180D01*
X725513Y134313D01*
X726112Y134712D01*
X726511Y135244D01*
G01X731003Y134180D02*
Y139503D01*
G01Y138172D02*
X731402Y138838D01*
X732001Y139370D01*
X732799Y139503D01*
X733498Y139370D01*
X734097Y138838D01*
X734396Y137906D01*
Y134180D01*
G01X748669D02*
Y142165D01*
X747472Y140568D01*
G01Y134180D02*
X749867D01*
G01X761645D02*
Y139503D01*
G01Y138039D02*
X761944Y138705D01*
X762444Y139237D01*
X763142Y139503D01*
X763841Y139237D01*
X764340Y138705D01*
X764639Y138039D01*
Y134180D01*
G01Y138039D02*
X764939Y138705D01*
X765438Y139237D01*
X766137Y139503D01*
X766835Y139237D01*
X767335Y138705D01*
X767634Y137906D01*
Y134180D01*
G01X772624Y139503D02*
Y134180D01*
G01Y141633D02*
X772425Y141766D01*
Y142032D01*
X772624Y142165D01*
X772824Y142032D01*
Y141766D01*
X772624Y141633D01*
G01X779112Y135111D02*
X779611Y134579D01*
X780310Y134180D01*
X780909D01*
X781508Y134446D01*
X781907Y134845D01*
X782107Y135377D01*
X782007Y136176D01*
X781608Y136575D01*
X779811Y137374D01*
X779412Y138306D01*
X779611Y138971D01*
X780011Y139370D01*
X780609Y139503D01*
X781208Y139370D01*
X781807Y138971D01*
G01X788395Y132716D02*
X788794Y134446D01*
G01X802768Y131518D02*
Y139503D01*
G01Y138306D02*
X803267Y138971D01*
X803766Y139370D01*
X804564Y139503D01*
X805263Y139370D01*
X805962Y138705D01*
X806261Y137773D01*
X806361Y136842D01*
X806261Y135910D01*
X805962Y134978D01*
X805363Y134446D01*
X804564Y134180D01*
X803866Y134313D01*
X803167Y134712D01*
X802768Y135244D01*
G01X812549Y134180D02*
Y142165D01*
G01X819037Y137773D02*
X822231D01*
X821932Y138705D01*
X821433Y139237D01*
X820734Y139503D01*
X820035Y139370D01*
X819436Y138971D01*
X819037Y138039D01*
X818838Y137241D01*
Y136442D01*
X819037Y135644D01*
X819536Y134845D01*
X820135Y134313D01*
X820834Y134180D01*
X821533Y134446D01*
X822231Y135244D01*
G01X830316Y134180D02*
Y139503D01*
G01Y138572D02*
X829917Y139104D01*
X829318Y139370D01*
X828619Y139503D01*
X827921Y139237D01*
X827322Y138705D01*
X826922Y137906D01*
X826723Y136842D01*
X826922Y135777D01*
X827322Y134978D01*
X827921Y134446D01*
X828619Y134180D01*
X829318Y134313D01*
X829917Y134712D01*
X830316Y135244D01*
G01X835007Y135111D02*
X835506Y134579D01*
X836205Y134180D01*
X836804D01*
X837403Y134446D01*
X837802Y134845D01*
X838002Y135377D01*
X837902Y136176D01*
X837503Y136575D01*
X835706Y137374D01*
X835307Y138306D01*
X835506Y138971D01*
X835906Y139370D01*
X836504Y139503D01*
X837103Y139370D01*
X837702Y138971D01*
G01X842992Y137773D02*
X846186D01*
X845887Y138705D01*
X845388Y139237D01*
X844689Y139503D01*
X843990Y139370D01*
X843391Y138971D01*
X842992Y138039D01*
X842793Y137241D01*
Y136442D01*
X842992Y135644D01*
X843491Y134845D01*
X844090Y134313D01*
X844789Y134180D01*
X845488Y134446D01*
X846186Y135244D01*
G01X860459Y139503D02*
Y134180D01*
G01Y141633D02*
X860260Y141766D01*
Y142032D01*
X860459Y142165D01*
X860659Y142032D01*
Y141766D01*
X860459Y141633D01*
G01X866947Y135111D02*
X867446Y134579D01*
X868145Y134180D01*
X868744D01*
X869343Y134446D01*
X869742Y134845D01*
X869942Y135377D01*
X869842Y136176D01*
X869443Y136575D01*
X867646Y137374D01*
X867247Y138306D01*
X867446Y138971D01*
X867846Y139370D01*
X868444Y139503D01*
X869043Y139370D01*
X869642Y138971D01*
G01X874932Y135111D02*
X875431Y134579D01*
X876130Y134180D01*
X876729D01*
X877328Y134446D01*
X877727Y134845D01*
X877927Y135377D01*
X877827Y136176D01*
X877428Y136575D01*
X875631Y137374D01*
X875232Y138306D01*
X875431Y138971D01*
X875831Y139370D01*
X876429Y139503D01*
X877028Y139370D01*
X877627Y138971D01*
G01X882718Y139503D02*
Y135777D01*
X883117Y134845D01*
X883716Y134313D01*
X884414Y134180D01*
X885113Y134313D01*
X885712Y134845D01*
X886111Y135777D01*
G01Y134180D02*
Y139503D01*
G01X890902Y137773D02*
X894096D01*
X893797Y138705D01*
X893298Y139237D01*
X892599Y139503D01*
X891900Y139370D01*
X891301Y138971D01*
X890902Y138039D01*
X890703Y137241D01*
Y136442D01*
X890902Y135644D01*
X891401Y134845D01*
X892000Y134313D01*
X892699Y134180D01*
X893398Y134446D01*
X894096Y135244D01*
G01X906872Y137773D02*
X910066D01*
X909767Y138705D01*
X909268Y139237D01*
X908569Y139503D01*
X907870Y139370D01*
X907271Y138971D01*
X906872Y138039D01*
X906673Y137241D01*
Y136442D01*
X906872Y135644D01*
X907371Y134845D01*
X907970Y134313D01*
X908669Y134180D01*
X909368Y134446D01*
X910066Y135244D01*
G01X914658Y134180D02*
Y139503D01*
G01Y138172D02*
X915057Y138838D01*
X915656Y139370D01*
X916454Y139503D01*
X917153Y139370D01*
X917752Y138838D01*
X918051Y137906D01*
Y134180D01*
G01X922942Y132184D02*
X923641Y131651D01*
X924439Y131518D01*
X925138Y131651D01*
X925737Y132317D01*
X926136Y133248D01*
Y139503D01*
G01Y138439D02*
X925737Y138971D01*
X925138Y139370D01*
X924439Y139503D01*
X923641Y139237D01*
X923142Y138705D01*
X922742Y137773D01*
X922543Y136842D01*
X922643Y136043D01*
X923042Y135111D01*
X923641Y134446D01*
X924439Y134180D01*
X925038Y134313D01*
X925737Y134845D01*
X926136Y135377D01*
G01X932324Y139503D02*
Y134180D01*
G01Y141633D02*
X932125Y141766D01*
Y142032D01*
X932324Y142165D01*
X932524Y142032D01*
Y141766D01*
X932324Y141633D01*
G01X938613Y134180D02*
Y139503D01*
G01Y138172D02*
X939012Y138838D01*
X939611Y139370D01*
X940409Y139503D01*
X941108Y139370D01*
X941707Y138838D01*
X942006Y137906D01*
Y134180D01*
G01X946797Y137773D02*
X949991D01*
X949692Y138705D01*
X949193Y139237D01*
X948494Y139503D01*
X947795Y139370D01*
X947196Y138971D01*
X946797Y138039D01*
X946598Y137241D01*
Y136442D01*
X946797Y135644D01*
X947296Y134845D01*
X947895Y134313D01*
X948594Y134180D01*
X949293Y134446D01*
X949991Y135244D01*
G01X954782Y137773D02*
X957976D01*
X957677Y138705D01*
X957178Y139237D01*
X956479Y139503D01*
X955780Y139370D01*
X955181Y138971D01*
X954782Y138039D01*
X954583Y137241D01*
Y136442D01*
X954782Y135644D01*
X955281Y134845D01*
X955880Y134313D01*
X956579Y134180D01*
X957278Y134446D01*
X957976Y135244D01*
G01X962867Y134180D02*
Y139503D01*
G01Y138439D02*
X963366Y138971D01*
X963865Y139370D01*
X964564Y139503D01*
X965063Y139370D01*
X965662Y138971D01*
G01X972249Y139503D02*
Y134180D01*
G01Y141633D02*
X972050Y141766D01*
Y142032D01*
X972249Y142165D01*
X972449Y142032D01*
Y141766D01*
X972249Y141633D01*
G01X978538Y134180D02*
Y139503D01*
G01Y138172D02*
X978937Y138838D01*
X979536Y139370D01*
X980334Y139503D01*
X981033Y139370D01*
X981632Y138838D01*
X981931Y137906D01*
Y134180D01*
G01X986822Y132184D02*
X987521Y131651D01*
X988319Y131518D01*
X989018Y131651D01*
X989617Y132317D01*
X990016Y133248D01*
Y139503D01*
G01Y138439D02*
X989617Y138971D01*
X989018Y139370D01*
X988319Y139503D01*
X987521Y139237D01*
X987022Y138705D01*
X986622Y137773D01*
X986423Y136842D01*
X986523Y136043D01*
X986922Y135111D01*
X987521Y134446D01*
X988319Y134180D01*
X988918Y134313D01*
X989617Y134845D01*
X990016Y135377D01*
G01X1005986Y131518D02*
Y139503D01*
G01Y138306D02*
X1005487Y138971D01*
X1004888Y139370D01*
X1004189Y139503D01*
X1003591Y139370D01*
X1002892Y138705D01*
X1002493Y137773D01*
X1002393Y136842D01*
X1002493Y135910D01*
X1002892Y134978D01*
X1003591Y134313D01*
X1004189Y134180D01*
X1004888Y134313D01*
X1005487Y134712D01*
X1005986Y135377D01*
G01X1010478Y139503D02*
Y135777D01*
X1010877Y134845D01*
X1011476Y134313D01*
X1012174Y134180D01*
X1012873Y134313D01*
X1013472Y134845D01*
X1013871Y135777D01*
G01Y134180D02*
Y139503D01*
G01X1018662Y137773D02*
X1021856D01*
X1021557Y138705D01*
X1021058Y139237D01*
X1020359Y139503D01*
X1019660Y139370D01*
X1019061Y138971D01*
X1018662Y138039D01*
X1018463Y137241D01*
Y136442D01*
X1018662Y135644D01*
X1019161Y134845D01*
X1019760Y134313D01*
X1020459Y134180D01*
X1021158Y134446D01*
X1021856Y135244D01*
G01X1026747Y134180D02*
Y139503D01*
G01Y138439D02*
X1027246Y138971D01*
X1027745Y139370D01*
X1028444Y139503D01*
X1028943Y139370D01*
X1029542Y138971D01*
G01X1034033Y131785D02*
X1034632Y131518D01*
X1035431Y131785D01*
X1035930Y132317D01*
X1036329Y132982D01*
X1036928Y135111D01*
X1038226Y139503D01*
G01X1035031D02*
X1036928Y135111D01*
G01X1044114Y133914D02*
X1043915Y134047D01*
Y134313D01*
X1044114Y134446D01*
X1044314Y134313D01*
Y134047D01*
X1044114Y133914D01*
G01X595559Y154465D02*
Y148742D01*
X595958Y147544D01*
X596756Y146746D01*
X597754Y146480D01*
X598753Y146746D01*
X599551Y147544D01*
X599950Y148742D01*
Y154465D01*
G01X604043Y146480D02*
Y151803D01*
G01Y150472D02*
X604442Y151138D01*
X605041Y151670D01*
X605839Y151803D01*
X606538Y151670D01*
X607137Y151138D01*
X607436Y150206D01*
Y146480D01*
G01X613724Y151803D02*
Y146480D01*
G01Y153933D02*
X613525Y154066D01*
Y154332D01*
X613724Y154465D01*
X613924Y154332D01*
Y154066D01*
X613724Y153933D01*
G01X621709Y154465D02*
Y146480D01*
G01X620312Y151803D02*
X623107D01*
G01X639276Y151138D02*
X638578Y151670D01*
X637979Y151803D01*
X637180Y151537D01*
X636581Y151005D01*
X636182Y150073D01*
X636082Y149142D01*
X636182Y148210D01*
X636581Y147411D01*
X637180Y146746D01*
X637979Y146480D01*
X638678Y146746D01*
X639276Y147278D01*
G01X645664Y146480D02*
X645066Y146613D01*
X644467Y147145D01*
X644067Y148077D01*
X643868Y149142D01*
X644067Y150206D01*
X644467Y151138D01*
X645066Y151670D01*
X645664Y151803D01*
X646263Y151670D01*
X646862Y151138D01*
X647261Y150206D01*
X647361Y149142D01*
X647261Y148077D01*
X646862Y147145D01*
X646263Y146613D01*
X645664Y146480D01*
G01X651953D02*
Y151803D01*
G01Y150472D02*
X652352Y151138D01*
X652951Y151670D01*
X653749Y151803D01*
X654448Y151670D01*
X655047Y151138D01*
X655346Y150206D01*
Y146480D01*
G01X659838Y151803D02*
X661634Y146480D01*
X663431Y151803D01*
G01X668122Y150073D02*
X671316D01*
X671017Y151005D01*
X670518Y151537D01*
X669819Y151803D01*
X669120Y151670D01*
X668521Y151271D01*
X668122Y150339D01*
X667923Y149541D01*
Y148742D01*
X668122Y147944D01*
X668621Y147145D01*
X669220Y146613D01*
X669919Y146480D01*
X670618Y146746D01*
X671316Y147544D01*
G01X676207Y146480D02*
Y151803D01*
G01Y150739D02*
X676706Y151271D01*
X677205Y151670D01*
X677904Y151803D01*
X678403Y151670D01*
X679002Y151271D01*
G01X684092Y147411D02*
X684591Y146879D01*
X685290Y146480D01*
X685889D01*
X686488Y146746D01*
X686887Y147145D01*
X687087Y147677D01*
X686987Y148476D01*
X686588Y148875D01*
X684791Y149674D01*
X684392Y150606D01*
X684591Y151271D01*
X684991Y151670D01*
X685589Y151803D01*
X686188Y151670D01*
X686787Y151271D01*
G01X693574Y151803D02*
Y146480D01*
G01Y153933D02*
X693375Y154066D01*
Y154332D01*
X693574Y154465D01*
X693774Y154332D01*
Y154066D01*
X693574Y153933D01*
G01X701559Y146480D02*
X700961Y146613D01*
X700362Y147145D01*
X699962Y148077D01*
X699763Y149142D01*
X699962Y150206D01*
X700362Y151138D01*
X700961Y151670D01*
X701559Y151803D01*
X702158Y151670D01*
X702757Y151138D01*
X703156Y150206D01*
X703256Y149142D01*
X703156Y148077D01*
X702757Y147145D01*
X702158Y146613D01*
X701559Y146480D01*
G01X707848D02*
Y151803D01*
G01Y150472D02*
X708247Y151138D01*
X708846Y151670D01*
X709644Y151803D01*
X710343Y151670D01*
X710942Y151138D01*
X711241Y150206D01*
Y146480D01*
G01X724017Y150073D02*
X727211D01*
X726912Y151005D01*
X726413Y151537D01*
X725714Y151803D01*
X725015Y151670D01*
X724416Y151271D01*
X724017Y150339D01*
X723818Y149541D01*
Y148742D01*
X724017Y147944D01*
X724516Y147145D01*
X725115Y146613D01*
X725814Y146480D01*
X726513Y146746D01*
X727211Y147544D01*
G01X732102Y146480D02*
Y151803D01*
G01Y150739D02*
X732601Y151271D01*
X733100Y151670D01*
X733799Y151803D01*
X734298Y151670D01*
X734897Y151271D01*
G01X740087Y146480D02*
Y151803D01*
G01Y150739D02*
X740586Y151271D01*
X741085Y151670D01*
X741784Y151803D01*
X742283Y151670D01*
X742882Y151271D01*
G01X749469Y146480D02*
X748871Y146613D01*
X748272Y147145D01*
X747872Y148077D01*
X747673Y149142D01*
X747872Y150206D01*
X748272Y151138D01*
X748871Y151670D01*
X749469Y151803D01*
X750068Y151670D01*
X750667Y151138D01*
X751066Y150206D01*
X751166Y149142D01*
X751066Y148077D01*
X750667Y147145D01*
X750068Y146613D01*
X749469Y146480D01*
G01X756057D02*
Y151803D01*
G01Y150739D02*
X756556Y151271D01*
X757055Y151670D01*
X757754Y151803D01*
X758253Y151670D01*
X758852Y151271D01*
G01X771628Y146480D02*
Y154465D01*
G01Y150472D02*
X772127Y151271D01*
X772726Y151670D01*
X773325Y151803D01*
X774223Y151537D01*
X774822Y151005D01*
X775221Y150073D01*
Y149009D01*
X775021Y147944D01*
X774622Y147145D01*
X773924Y146613D01*
X773325Y146480D01*
X772726Y146613D01*
X772127Y147012D01*
X771628Y147677D01*
G01X779912Y150073D02*
X783106D01*
X782807Y151005D01*
X782308Y151537D01*
X781609Y151803D01*
X780910Y151670D01*
X780311Y151271D01*
X779912Y150339D01*
X779713Y149541D01*
Y148742D01*
X779912Y147944D01*
X780411Y147145D01*
X781010Y146613D01*
X781709Y146480D01*
X782408Y146746D01*
X783106Y147544D01*
G01X789394Y154465D02*
Y146480D01*
G01X787997Y151803D02*
X790792D01*
G01X794884D02*
X796082Y146480D01*
X797379Y151803D01*
X798677Y146480D01*
X799875Y151803D01*
G01X803867Y150073D02*
X807061D01*
X806762Y151005D01*
X806263Y151537D01*
X805564Y151803D01*
X804865Y151670D01*
X804266Y151271D01*
X803867Y150339D01*
X803668Y149541D01*
Y148742D01*
X803867Y147944D01*
X804366Y147145D01*
X804965Y146613D01*
X805664Y146480D01*
X806363Y146746D01*
X807061Y147544D01*
G01X811852Y150073D02*
X815046D01*
X814747Y151005D01*
X814248Y151537D01*
X813549Y151803D01*
X812850Y151670D01*
X812251Y151271D01*
X811852Y150339D01*
X811653Y149541D01*
Y148742D01*
X811852Y147944D01*
X812351Y147145D01*
X812950Y146613D01*
X813649Y146480D01*
X814348Y146746D01*
X815046Y147544D01*
G01X819638Y146480D02*
Y151803D01*
G01Y150472D02*
X820037Y151138D01*
X820636Y151670D01*
X821434Y151803D01*
X822133Y151670D01*
X822732Y151138D01*
X823031Y150206D01*
Y146480D01*
G01X834310D02*
Y151803D01*
G01Y150339D02*
X834609Y151005D01*
X835109Y151537D01*
X835807Y151803D01*
X836506Y151537D01*
X837005Y151005D01*
X837304Y150339D01*
Y146480D01*
G01Y150339D02*
X837604Y151005D01*
X838103Y151537D01*
X838802Y151803D01*
X839500Y151537D01*
X840000Y151005D01*
X840299Y150206D01*
Y146480D01*
G01X843792Y150073D02*
X846986D01*
X846687Y151005D01*
X846188Y151537D01*
X845489Y151803D01*
X844790Y151670D01*
X844191Y151271D01*
X843792Y150339D01*
X843593Y149541D01*
Y148742D01*
X843792Y147944D01*
X844291Y147145D01*
X844890Y146613D01*
X845589Y146480D01*
X846288Y146746D01*
X846986Y147544D01*
G01X853274Y154465D02*
Y146480D01*
G01X851877Y151803D02*
X854672D01*
G01X859862Y146480D02*
Y151803D01*
G01Y150739D02*
X860361Y151271D01*
X860860Y151670D01*
X861559Y151803D01*
X862058Y151670D01*
X862657Y151271D01*
G01X869244Y151803D02*
Y146480D01*
G01Y153933D02*
X869045Y154066D01*
Y154332D01*
X869244Y154465D01*
X869444Y154332D01*
Y154066D01*
X869244Y153933D01*
G01X878826Y151138D02*
X878128Y151670D01*
X877529Y151803D01*
X876730Y151537D01*
X876131Y151005D01*
X875732Y150073D01*
X875632Y149142D01*
X875732Y148210D01*
X876131Y147411D01*
X876730Y146746D01*
X877529Y146480D01*
X878228Y146746D01*
X878826Y147278D01*
G01X894996Y146480D02*
Y151803D01*
G01Y150872D02*
X894597Y151404D01*
X893998Y151670D01*
X893299Y151803D01*
X892601Y151537D01*
X892002Y151005D01*
X891602Y150206D01*
X891403Y149142D01*
X891602Y148077D01*
X892002Y147278D01*
X892601Y146746D01*
X893299Y146480D01*
X893998Y146613D01*
X894597Y147012D01*
X894996Y147544D01*
G01X899488Y146480D02*
Y151803D01*
G01Y150472D02*
X899887Y151138D01*
X900486Y151670D01*
X901284Y151803D01*
X901983Y151670D01*
X902582Y151138D01*
X902881Y150206D01*
Y146480D01*
G01X910966Y154465D02*
Y146480D01*
G01Y147677D02*
X910567Y147012D01*
X909968Y146613D01*
X909269Y146480D01*
X908471Y146746D01*
X907872Y147411D01*
X907473Y148210D01*
X907373Y149142D01*
X907473Y150073D01*
X907872Y150872D01*
X908471Y151537D01*
X909269Y151803D01*
X909968Y151670D01*
X910467Y151404D01*
X910966Y150872D01*
G01X927136Y146480D02*
X923143D01*
Y154465D01*
X927136D01*
G01X925539Y150606D02*
X923143D01*
G01X931428Y146480D02*
Y151803D01*
G01Y150472D02*
X931827Y151138D01*
X932426Y151670D01*
X933224Y151803D01*
X933923Y151670D01*
X934522Y151138D01*
X934821Y150206D01*
Y146480D01*
G01X939712Y144484D02*
X940411Y143951D01*
X941209Y143818D01*
X941908Y143951D01*
X942507Y144617D01*
X942906Y145548D01*
Y151803D01*
G01Y150739D02*
X942507Y151271D01*
X941908Y151670D01*
X941209Y151803D01*
X940411Y151537D01*
X939912Y151005D01*
X939512Y150073D01*
X939313Y149142D01*
X939413Y148343D01*
X939812Y147411D01*
X940411Y146746D01*
X941209Y146480D01*
X941808Y146613D01*
X942507Y147145D01*
X942906Y147677D01*
G01X949094Y146480D02*
Y154465D01*
G01X957079Y151803D02*
Y146480D01*
G01Y153933D02*
X956880Y154066D01*
Y154332D01*
X957079Y154465D01*
X957279Y154332D01*
Y154066D01*
X957079Y153933D01*
G01X963567Y147411D02*
X964066Y146879D01*
X964765Y146480D01*
X965364D01*
X965963Y146746D01*
X966362Y147145D01*
X966562Y147677D01*
X966462Y148476D01*
X966063Y148875D01*
X964266Y149674D01*
X963867Y150606D01*
X964066Y151271D01*
X964466Y151670D01*
X965064Y151803D01*
X965663Y151670D01*
X966262Y151271D01*
G01X971353Y146480D02*
Y154465D01*
G01Y150606D02*
X971852Y151271D01*
X972351Y151670D01*
X973149Y151803D01*
X973748Y151670D01*
X974447Y151138D01*
X974746Y150339D01*
Y146480D01*
G01X987522Y147411D02*
X988021Y146879D01*
X988720Y146480D01*
X989319D01*
X989918Y146746D01*
X990317Y147145D01*
X990517Y147677D01*
X990417Y148476D01*
X990018Y148875D01*
X988221Y149674D01*
X987822Y150606D01*
X988021Y151271D01*
X988421Y151670D01*
X989019Y151803D01*
X989618Y151670D01*
X990217Y151271D01*
G01X994908Y144085D02*
X995507Y143818D01*
X996306Y144085D01*
X996805Y144617D01*
X997204Y145282D01*
X997803Y147411D01*
X999101Y151803D01*
G01X995906D02*
X997803Y147411D01*
G01X1003492D02*
X1003991Y146879D01*
X1004690Y146480D01*
X1005289D01*
X1005888Y146746D01*
X1006287Y147145D01*
X1006487Y147677D01*
X1006387Y148476D01*
X1005988Y148875D01*
X1004191Y149674D01*
X1003792Y150606D01*
X1003991Y151271D01*
X1004391Y151670D01*
X1004989Y151803D01*
X1005588Y151670D01*
X1006187Y151271D01*
G01X1012974Y154465D02*
Y146480D01*
G01X1011577Y151803D02*
X1014372D01*
G01X1019462Y150073D02*
X1022656D01*
X1022357Y151005D01*
X1021858Y151537D01*
X1021159Y151803D01*
X1020460Y151670D01*
X1019861Y151271D01*
X1019462Y150339D01*
X1019263Y149541D01*
Y148742D01*
X1019462Y147944D01*
X1019961Y147145D01*
X1020560Y146613D01*
X1021259Y146480D01*
X1021958Y146746D01*
X1022656Y147544D01*
G01X1025950Y146480D02*
Y151803D01*
G01Y150339D02*
X1026249Y151005D01*
X1026749Y151537D01*
X1027447Y151803D01*
X1028146Y151537D01*
X1028645Y151005D01*
X1028944Y150339D01*
Y146480D01*
G01Y150339D02*
X1029244Y151005D01*
X1029743Y151537D01*
X1030442Y151803D01*
X1031140Y151537D01*
X1031640Y151005D01*
X1031939Y150206D01*
Y146480D01*
G01X1044914Y151803D02*
Y146480D01*
G01Y153933D02*
X1044715Y154066D01*
Y154332D01*
X1044914Y154465D01*
X1045114Y154332D01*
Y154066D01*
X1044914Y153933D01*
G01X1051402Y147411D02*
X1051901Y146879D01*
X1052600Y146480D01*
X1053199D01*
X1053798Y146746D01*
X1054197Y147145D01*
X1054397Y147677D01*
X1054297Y148476D01*
X1053898Y148875D01*
X1052101Y149674D01*
X1051702Y150606D01*
X1051901Y151271D01*
X1052301Y151670D01*
X1052899Y151803D01*
X1053498Y151670D01*
X1054097Y151271D01*
G01X1068869Y146480D02*
Y154465D01*
G01X1075357Y150073D02*
X1078551D01*
X1078252Y151005D01*
X1077753Y151537D01*
X1077054Y151803D01*
X1076355Y151670D01*
X1075756Y151271D01*
X1075357Y150339D01*
X1075158Y149541D01*
Y148742D01*
X1075357Y147944D01*
X1075856Y147145D01*
X1076455Y146613D01*
X1077154Y146480D01*
X1077853Y146746D01*
X1078551Y147544D01*
G01X1083342Y147411D02*
X1083841Y146879D01*
X1084540Y146480D01*
X1085139D01*
X1085738Y146746D01*
X1086137Y147145D01*
X1086337Y147677D01*
X1086237Y148476D01*
X1085838Y148875D01*
X1084041Y149674D01*
X1083642Y150606D01*
X1083841Y151271D01*
X1084241Y151670D01*
X1084839Y151803D01*
X1085438Y151670D01*
X1086037Y151271D01*
G01X1091327Y147411D02*
X1091826Y146879D01*
X1092525Y146480D01*
X1093124D01*
X1093723Y146746D01*
X1094122Y147145D01*
X1094322Y147677D01*
X1094222Y148476D01*
X1093823Y148875D01*
X1092026Y149674D01*
X1091627Y150606D01*
X1091826Y151271D01*
X1092226Y151670D01*
X1092824Y151803D01*
X1093423Y151670D01*
X1094022Y151271D01*
G01X1108794Y154465D02*
Y146480D01*
G01X1107397Y151803D02*
X1110192D01*
G01X1115083Y146480D02*
Y154465D01*
G01Y150606D02*
X1115582Y151271D01*
X1116081Y151670D01*
X1116879Y151803D01*
X1117478Y151670D01*
X1118177Y151138D01*
X1118476Y150339D01*
Y146480D01*
G01X1126561D02*
Y151803D01*
G01Y150872D02*
X1126162Y151404D01*
X1125563Y151670D01*
X1124864Y151803D01*
X1124166Y151537D01*
X1123567Y151005D01*
X1123167Y150206D01*
X1122968Y149142D01*
X1123167Y148077D01*
X1123567Y147278D01*
X1124166Y146746D01*
X1124864Y146480D01*
X1125563Y146613D01*
X1126162Y147012D01*
X1126561Y147544D01*
G01X1131053Y146480D02*
Y151803D01*
G01Y150472D02*
X1131452Y151138D01*
X1132051Y151670D01*
X1132849Y151803D01*
X1133548Y151670D01*
X1134147Y151138D01*
X1134446Y150206D01*
Y146480D01*
G01X1148719D02*
Y154465D01*
X1147522Y152868D01*
G01Y146480D02*
X1149917D01*
G01X1161695D02*
Y151803D01*
G01Y150339D02*
X1161994Y151005D01*
X1162494Y151537D01*
X1163192Y151803D01*
X1163891Y151537D01*
X1164390Y151005D01*
X1164689Y150339D01*
Y146480D01*
G01Y150339D02*
X1164989Y151005D01*
X1165488Y151537D01*
X1166187Y151803D01*
X1166885Y151537D01*
X1167385Y151005D01*
X1167684Y150206D01*
Y146480D01*
G01X1172674Y151803D02*
Y146480D01*
G01Y153933D02*
X1172475Y154066D01*
Y154332D01*
X1172674Y154465D01*
X1172874Y154332D01*
Y154066D01*
X1172674Y153933D01*
G01X1180659Y146480D02*
Y154465D01*
G01X1188445Y145016D02*
X1188844Y146746D01*
G01X1202818Y143818D02*
Y151803D01*
G01Y150606D02*
X1203317Y151271D01*
X1203816Y151670D01*
X1204614Y151803D01*
X1205313Y151670D01*
X1206012Y151005D01*
X1206311Y150073D01*
X1206411Y149142D01*
X1206311Y148210D01*
X1206012Y147278D01*
X1205413Y146746D01*
X1204614Y146480D01*
X1203916Y146613D01*
X1203217Y147012D01*
X1202818Y147544D01*
G01X1212599Y146480D02*
Y154465D01*
G01X1219087Y150073D02*
X1222281D01*
X1221982Y151005D01*
X1221483Y151537D01*
X1220784Y151803D01*
X1220085Y151670D01*
X1219486Y151271D01*
X1219087Y150339D01*
X1218888Y149541D01*
Y148742D01*
X1219087Y147944D01*
X1219586Y147145D01*
X1220185Y146613D01*
X1220884Y146480D01*
X1221583Y146746D01*
X1222281Y147544D01*
G01X1230366Y146480D02*
Y151803D01*
G01Y150872D02*
X1229967Y151404D01*
X1229368Y151670D01*
X1228669Y151803D01*
X1227971Y151537D01*
X1227372Y151005D01*
X1226972Y150206D01*
X1226773Y149142D01*
X1226972Y148077D01*
X1227372Y147278D01*
X1227971Y146746D01*
X1228669Y146480D01*
X1229368Y146613D01*
X1229967Y147012D01*
X1230366Y147544D01*
G01X1235057Y147411D02*
X1235556Y146879D01*
X1236255Y146480D01*
X1236854D01*
X1237453Y146746D01*
X1237852Y147145D01*
X1238052Y147677D01*
X1237952Y148476D01*
X1237553Y148875D01*
X1235756Y149674D01*
X1235357Y150606D01*
X1235556Y151271D01*
X1235956Y151670D01*
X1236554Y151803D01*
X1237153Y151670D01*
X1237752Y151271D01*
G01X1243042Y150073D02*
X1246236D01*
X1245937Y151005D01*
X1245438Y151537D01*
X1244739Y151803D01*
X1244040Y151670D01*
X1243441Y151271D01*
X1243042Y150339D01*
X1242843Y149541D01*
Y148742D01*
X1243042Y147944D01*
X1243541Y147145D01*
X1244140Y146613D01*
X1244839Y146480D01*
X1245538Y146746D01*
X1246236Y147544D01*
G01X1259911Y146480D02*
Y153267D01*
X1260110Y153933D01*
X1260509Y154332D01*
X1261108Y154465D01*
X1261707Y154199D01*
X1262007Y153533D01*
G01X1260809Y151271D02*
X1258813D01*
G01X1268494Y146480D02*
X1267896Y146613D01*
X1267297Y147145D01*
X1266897Y148077D01*
X1266698Y149142D01*
X1266897Y150206D01*
X1267297Y151138D01*
X1267896Y151670D01*
X1268494Y151803D01*
X1269093Y151670D01*
X1269692Y151138D01*
X1270091Y150206D01*
X1270191Y149142D01*
X1270091Y148077D01*
X1269692Y147145D01*
X1269093Y146613D01*
X1268494Y146480D01*
G01X1276479D02*
Y154465D01*
G01X1284464Y146480D02*
Y154465D01*
G01X1292449Y146480D02*
X1291851Y146613D01*
X1291252Y147145D01*
X1290852Y148077D01*
X1290653Y149142D01*
X1290852Y150206D01*
X1291252Y151138D01*
X1291851Y151670D01*
X1292449Y151803D01*
X1293048Y151670D01*
X1293647Y151138D01*
X1294046Y150206D01*
X1294146Y149142D01*
X1294046Y148077D01*
X1293647Y147145D01*
X1293048Y146613D01*
X1292449Y146480D01*
G01X1297939Y151803D02*
X1299137Y146480D01*
X1300434Y151803D01*
X1301732Y146480D01*
X1302930Y151803D01*
G01X1313410Y146480D02*
Y151803D01*
G01Y150339D02*
X1313709Y151005D01*
X1314209Y151537D01*
X1314907Y151803D01*
X1315606Y151537D01*
X1316105Y151005D01*
X1316404Y150339D01*
Y146480D01*
G01Y150339D02*
X1316704Y151005D01*
X1317203Y151537D01*
X1317902Y151803D01*
X1318600Y151537D01*
X1319100Y151005D01*
X1319399Y150206D01*
Y146480D01*
G01X1322892Y150073D02*
X1326086D01*
X1325787Y151005D01*
X1325288Y151537D01*
X1324589Y151803D01*
X1323890Y151670D01*
X1323291Y151271D01*
X1322892Y150339D01*
X1322693Y149541D01*
Y148742D01*
X1322892Y147944D01*
X1323391Y147145D01*
X1323990Y146613D01*
X1324689Y146480D01*
X1325388Y146746D01*
X1326086Y147544D01*
G01X1333971Y151138D02*
X1333273Y151670D01*
X1332674Y151803D01*
X1331875Y151537D01*
X1331276Y151005D01*
X1330877Y150073D01*
X1330777Y149142D01*
X1330877Y148210D01*
X1331276Y147411D01*
X1331875Y146746D01*
X1332674Y146480D01*
X1333373Y146746D01*
X1333971Y147278D01*
G01X1338663Y146480D02*
Y154465D01*
G01Y150606D02*
X1339162Y151271D01*
X1339661Y151670D01*
X1340459Y151803D01*
X1341058Y151670D01*
X1341757Y151138D01*
X1342056Y150339D01*
Y146480D01*
G01X1350141D02*
Y151803D01*
G01Y150872D02*
X1349742Y151404D01*
X1349143Y151670D01*
X1348444Y151803D01*
X1347746Y151537D01*
X1347147Y151005D01*
X1346747Y150206D01*
X1346548Y149142D01*
X1346747Y148077D01*
X1347147Y147278D01*
X1347746Y146746D01*
X1348444Y146480D01*
X1349143Y146613D01*
X1349742Y147012D01*
X1350141Y147544D01*
G01X1354633Y146480D02*
Y151803D01*
G01Y150472D02*
X1355032Y151138D01*
X1355631Y151670D01*
X1356429Y151803D01*
X1357128Y151670D01*
X1357727Y151138D01*
X1358026Y150206D01*
Y146480D01*
G01X1364314Y151803D02*
Y146480D01*
G01Y153933D02*
X1364115Y154066D01*
Y154332D01*
X1364314Y154465D01*
X1364514Y154332D01*
Y154066D01*
X1364314Y153933D01*
G01X1373896Y151138D02*
X1373198Y151670D01*
X1372599Y151803D01*
X1371800Y151537D01*
X1371201Y151005D01*
X1370802Y150073D01*
X1370702Y149142D01*
X1370802Y148210D01*
X1371201Y147411D01*
X1371800Y146746D01*
X1372599Y146480D01*
X1373298Y146746D01*
X1373896Y147278D01*
G01X1382081Y146480D02*
Y151803D01*
G01Y150872D02*
X1381682Y151404D01*
X1381083Y151670D01*
X1380384Y151803D01*
X1379686Y151537D01*
X1379087Y151005D01*
X1378687Y150206D01*
X1378488Y149142D01*
X1378687Y148077D01*
X1379087Y147278D01*
X1379686Y146746D01*
X1380384Y146480D01*
X1381083Y146613D01*
X1381682Y147012D01*
X1382081Y147544D01*
G01X1388269Y146480D02*
Y154465D01*
G01X1406036D02*
Y146480D01*
G01Y147677D02*
X1405637Y147012D01*
X1405038Y146613D01*
X1404339Y146480D01*
X1403541Y146746D01*
X1402942Y147411D01*
X1402543Y148210D01*
X1402443Y149142D01*
X1402543Y150073D01*
X1402942Y150872D01*
X1403541Y151537D01*
X1404339Y151803D01*
X1405038Y151670D01*
X1405537Y151404D01*
X1406036Y150872D01*
G01X1410827Y146480D02*
Y151803D01*
G01Y150739D02*
X1411326Y151271D01*
X1411825Y151670D01*
X1412524Y151803D01*
X1413023Y151670D01*
X1413622Y151271D01*
G01X1422006Y146480D02*
Y151803D01*
G01Y150872D02*
X1421607Y151404D01*
X1421008Y151670D01*
X1420309Y151803D01*
X1419611Y151537D01*
X1419012Y151005D01*
X1418612Y150206D01*
X1418413Y149142D01*
X1418612Y148077D01*
X1419012Y147278D01*
X1419611Y146746D01*
X1420309Y146480D01*
X1421008Y146613D01*
X1421607Y147012D01*
X1422006Y147544D01*
G01X1425699Y151803D02*
X1426897Y146480D01*
X1428194Y151803D01*
X1429492Y146480D01*
X1430690Y151803D01*
G01X1436179D02*
Y146480D01*
G01Y153933D02*
X1435980Y154066D01*
Y154332D01*
X1436179Y154465D01*
X1436379Y154332D01*
Y154066D01*
X1436179Y153933D01*
G01X1442468Y146480D02*
Y151803D01*
G01Y150472D02*
X1442867Y151138D01*
X1443466Y151670D01*
X1444264Y151803D01*
X1444963Y151670D01*
X1445562Y151138D01*
X1445861Y150206D01*
Y146480D01*
G01X1450752Y144484D02*
X1451451Y143951D01*
X1452249Y143818D01*
X1452948Y143951D01*
X1453547Y144617D01*
X1453946Y145548D01*
Y151803D01*
G01Y150739D02*
X1453547Y151271D01*
X1452948Y151670D01*
X1452249Y151803D01*
X1451451Y151537D01*
X1450952Y151005D01*
X1450552Y150073D01*
X1450353Y149142D01*
X1450453Y148343D01*
X1450852Y147411D01*
X1451451Y146746D01*
X1452249Y146480D01*
X1452848Y146613D01*
X1453547Y147145D01*
X1453946Y147677D01*
G01X1459436Y144085D02*
X1460833Y145948D01*
Y147811D01*
X1459436D01*
Y145948D01*
X1460833D01*
G01Y149142D02*
Y151005D01*
X1459436D01*
Y149142D01*
X1460833D01*
G01X595359Y166265D02*
Y160542D01*
X595758Y159344D01*
X596556Y158546D01*
X597554Y158280D01*
X598553Y158546D01*
X599351Y159344D01*
X599750Y160542D01*
Y166265D01*
G01X603843Y158280D02*
Y163603D01*
G01Y162272D02*
X604242Y162938D01*
X604841Y163470D01*
X605639Y163603D01*
X606338Y163470D01*
X606937Y162938D01*
X607236Y162006D01*
Y158280D01*
G01X613524Y163603D02*
Y158280D01*
G01Y165733D02*
X613325Y165866D01*
Y166132D01*
X613524Y166265D01*
X613724Y166132D01*
Y165866D01*
X613524Y165733D01*
G01X621509Y166265D02*
Y158280D01*
G01X620112Y163603D02*
X622907D01*
G01X639076Y162938D02*
X638378Y163470D01*
X637779Y163603D01*
X636980Y163337D01*
X636381Y162805D01*
X635982Y161873D01*
X635882Y160942D01*
X635982Y160010D01*
X636381Y159211D01*
X636980Y158546D01*
X637779Y158280D01*
X638478Y158546D01*
X639076Y159078D01*
G01X645464Y158280D02*
X644866Y158413D01*
X644267Y158945D01*
X643867Y159877D01*
X643668Y160942D01*
X643867Y162006D01*
X644267Y162938D01*
X644866Y163470D01*
X645464Y163603D01*
X646063Y163470D01*
X646662Y162938D01*
X647061Y162006D01*
X647161Y160942D01*
X647061Y159877D01*
X646662Y158945D01*
X646063Y158413D01*
X645464Y158280D01*
G01X651753D02*
Y163603D01*
G01Y162272D02*
X652152Y162938D01*
X652751Y163470D01*
X653549Y163603D01*
X654248Y163470D01*
X654847Y162938D01*
X655146Y162006D01*
Y158280D01*
G01X659638Y163603D02*
X661434Y158280D01*
X663231Y163603D01*
G01X667922Y161873D02*
X671116D01*
X670817Y162805D01*
X670318Y163337D01*
X669619Y163603D01*
X668920Y163470D01*
X668321Y163071D01*
X667922Y162139D01*
X667723Y161341D01*
Y160542D01*
X667922Y159744D01*
X668421Y158945D01*
X669020Y158413D01*
X669719Y158280D01*
X670418Y158546D01*
X671116Y159344D01*
G01X676007Y158280D02*
Y163603D01*
G01Y162539D02*
X676506Y163071D01*
X677005Y163470D01*
X677704Y163603D01*
X678203Y163470D01*
X678802Y163071D01*
G01X683892Y159211D02*
X684391Y158679D01*
X685090Y158280D01*
X685689D01*
X686288Y158546D01*
X686687Y158945D01*
X686887Y159477D01*
X686787Y160276D01*
X686388Y160675D01*
X684591Y161474D01*
X684192Y162406D01*
X684391Y163071D01*
X684791Y163470D01*
X685389Y163603D01*
X685988Y163470D01*
X686587Y163071D01*
G01X693374Y163603D02*
Y158280D01*
G01Y165733D02*
X693175Y165866D01*
Y166132D01*
X693374Y166265D01*
X693574Y166132D01*
Y165866D01*
X693374Y165733D01*
G01X701359Y158280D02*
X700761Y158413D01*
X700162Y158945D01*
X699762Y159877D01*
X699563Y160942D01*
X699762Y162006D01*
X700162Y162938D01*
X700761Y163470D01*
X701359Y163603D01*
X701958Y163470D01*
X702557Y162938D01*
X702956Y162006D01*
X703056Y160942D01*
X702956Y159877D01*
X702557Y158945D01*
X701958Y158413D01*
X701359Y158280D01*
G01X707648D02*
Y163603D01*
G01Y162272D02*
X708047Y162938D01*
X708646Y163470D01*
X709444Y163603D01*
X710143Y163470D01*
X710742Y162938D01*
X711041Y162006D01*
Y158280D01*
G01X725314Y163603D02*
Y158280D01*
G01Y165733D02*
X725115Y165866D01*
Y166132D01*
X725314Y166265D01*
X725514Y166132D01*
Y165866D01*
X725314Y165733D01*
G01X731802Y159211D02*
X732301Y158679D01*
X733000Y158280D01*
X733599D01*
X734198Y158546D01*
X734597Y158945D01*
X734797Y159477D01*
X734697Y160276D01*
X734298Y160675D01*
X732501Y161474D01*
X732102Y162406D01*
X732301Y163071D01*
X732701Y163470D01*
X733299Y163603D01*
X733898Y163470D01*
X734497Y163071D01*
G01X739787Y159211D02*
X740286Y158679D01*
X740985Y158280D01*
X741584D01*
X742183Y158546D01*
X742582Y158945D01*
X742782Y159477D01*
X742682Y160276D01*
X742283Y160675D01*
X740486Y161474D01*
X740087Y162406D01*
X740286Y163071D01*
X740686Y163470D01*
X741284Y163603D01*
X741883Y163470D01*
X742482Y163071D01*
G01X747573Y163603D02*
Y159877D01*
X747972Y158945D01*
X748571Y158413D01*
X749269Y158280D01*
X749968Y158413D01*
X750567Y158945D01*
X750966Y159877D01*
G01Y158280D02*
Y163603D01*
G01X755757Y161873D02*
X758951D01*
X758652Y162805D01*
X758153Y163337D01*
X757454Y163603D01*
X756755Y163470D01*
X756156Y163071D01*
X755757Y162139D01*
X755558Y161341D01*
Y160542D01*
X755757Y159744D01*
X756256Y158945D01*
X756855Y158413D01*
X757554Y158280D01*
X758253Y158546D01*
X758951Y159344D01*
G01X765239Y158014D02*
X765040Y158147D01*
Y158413D01*
X765239Y158546D01*
X765439Y158413D01*
Y158147D01*
X765239Y158014D01*
G01Y161607D02*
X765040Y161740D01*
Y162006D01*
X765239Y162139D01*
X765439Y162006D01*
Y161740D01*
X765239Y161607D01*
G01X605555Y209880D02*
Y217865D01*
X604358Y216268D01*
G01Y209880D02*
X606753D01*
G01X611644Y216534D02*
X612243Y217333D01*
X612942Y217732D01*
X613740Y217865D01*
X614738Y217599D01*
X615437Y216933D01*
X615637Y216135D01*
X615537Y215336D01*
X615137Y214671D01*
X613141Y213340D01*
X612243Y212409D01*
X611644Y211077D01*
X611444Y209880D01*
X615637D01*
G01X605581Y222380D02*
Y230365D01*
X604384Y228768D01*
G01Y222380D02*
X606779D01*
G01X613566D02*
Y230365D01*
X612369Y228768D01*
G01Y222380D02*
X614764D01*
G01X604954Y235380D02*
Y243365D01*
X603757Y241768D01*
G01Y235380D02*
X606152D01*
G01X612939Y243365D02*
X612141Y243099D01*
X611542Y242433D01*
X611143Y241635D01*
X610843Y240570D01*
X610744Y239372D01*
X610843Y238175D01*
X611143Y237110D01*
X611542Y236311D01*
X612141Y235646D01*
X612939Y235380D01*
X613738Y235646D01*
X614337Y236311D01*
X614736Y237110D01*
X615036Y238175D01*
X615135Y239372D01*
X615036Y240570D01*
X614736Y241635D01*
X614337Y242433D01*
X613738Y243099D01*
X612939Y243365D01*
G01X603258Y248811D02*
X603956Y248146D01*
X604755Y247880D01*
X605553Y248146D01*
X606252Y248944D01*
X606751Y250142D01*
X606951Y251340D01*
Y252804D01*
X606751Y254002D01*
X606252Y255066D01*
X605653Y255599D01*
X604954Y255865D01*
X604156Y255599D01*
X603557Y255066D01*
X603158Y254268D01*
X602958Y253203D01*
X603158Y252272D01*
X603657Y251340D01*
X604256Y250808D01*
X604954Y250675D01*
X605753Y250941D01*
X606352Y251606D01*
X606951Y252804D01*
G01X604954Y259880D02*
X605653Y260013D01*
X606452Y260412D01*
X606951Y261077D01*
X607150Y262009D01*
X606951Y262941D01*
X606352Y263739D01*
X605454Y264139D01*
X604455D01*
X603856Y264405D01*
X603357Y265070D01*
X603158Y266002D01*
X603457Y266933D01*
X604156Y267599D01*
X604954Y267865D01*
X605753Y267599D01*
X606452Y266933D01*
X606751Y266002D01*
X606551Y265070D01*
X606053Y264405D01*
X605454Y264139D01*
X604455D01*
X603557Y263739D01*
X602958Y262941D01*
X602759Y262009D01*
X602958Y261077D01*
X603457Y260412D01*
X604256Y260013D01*
X604954Y259880D01*
G01X605255Y272880D02*
X605454Y274610D01*
X605754Y276074D01*
X606153Y277405D01*
X606652Y278869D01*
X607451Y280865D01*
X603458D01*
G01X603558Y288379D02*
X604257Y289311D01*
X604856Y289843D01*
X605654Y290109D01*
X606353Y289843D01*
X606852Y289311D01*
X607251Y288512D01*
X607351Y287581D01*
X607251Y286782D01*
X606852Y285983D01*
X606253Y285318D01*
X605554Y285052D01*
X604756Y285318D01*
X604057Y286116D01*
X603658Y287314D01*
X603558Y288645D01*
X603758Y290375D01*
X604057Y291307D01*
X604556Y292238D01*
X605255Y292904D01*
X605954Y293037D01*
X606652Y292771D01*
X607151Y292105D01*
G01X603259Y299577D02*
X603857Y298912D01*
X604556Y298513D01*
X605454Y298380D01*
X606353Y298646D01*
X607051Y299178D01*
X607551Y300110D01*
X607650Y301175D01*
X607451Y302239D01*
X606952Y302905D01*
X606253Y303437D01*
X605554Y303570D01*
X604856Y303437D01*
X603957Y302905D01*
X604257Y306365D01*
X606952D01*
G01X606652Y309880D02*
Y317865D01*
X602959Y312142D01*
X607950D01*
G01X604058Y342034D02*
X604657Y342833D01*
X605356Y343232D01*
X606154Y343365D01*
X607152Y343099D01*
X607851Y342433D01*
X608051Y341635D01*
X607951Y340836D01*
X607551Y340171D01*
X605555Y338840D01*
X604657Y337909D01*
X604058Y336577D01*
X603858Y335380D01*
X608051D01*
G01X603759Y324477D02*
X604357Y323545D01*
X605156Y323013D01*
X606054Y322880D01*
X606853Y323013D01*
X607651Y323678D01*
X608150Y324477D01*
X608250Y325275D01*
X608051Y326207D01*
X607352Y326872D01*
X606653Y327139D01*
X605755D01*
G01X606653D02*
X607252Y327538D01*
X607751Y328203D01*
X607951Y329002D01*
X607751Y329800D01*
X607252Y330466D01*
X606354Y330865D01*
X605455Y330732D01*
X604557Y330199D01*
G01X605954Y347880D02*
Y355865D01*
X604757Y354268D01*
G01Y347880D02*
X607152D01*
G01X596159Y363380D02*
Y371365D01*
X600750Y363380D01*
Y371365D01*
G01X606439Y363380D02*
X605641Y363513D01*
X604942Y364045D01*
X604343Y364844D01*
X603944Y365775D01*
X603744Y366840D01*
Y367905D01*
X603944Y368970D01*
X604343Y369901D01*
X604942Y370699D01*
X605641Y371232D01*
X606439Y371365D01*
X607238Y371232D01*
X607937Y370699D01*
X608536Y369901D01*
X608935Y368970D01*
X609135Y367905D01*
Y366840D01*
X608935Y365775D01*
X608536Y364844D01*
X607937Y364045D01*
X607238Y363513D01*
X606439Y363380D01*
G01X614424Y363114D02*
X614225Y363247D01*
Y363513D01*
X614424Y363646D01*
X614624Y363513D01*
Y363247D01*
X614424Y363114D01*
G01X637958Y210380D02*
Y218365D01*
X640454D01*
X641252Y217966D01*
X641751Y217433D01*
X641951Y216369D01*
X641751Y215304D01*
X641152Y214639D01*
X640454Y214239D01*
X637958D01*
G01X640454D02*
X641951Y210380D01*
G01X647939D02*
X647341Y210513D01*
X646742Y211045D01*
X646342Y211977D01*
X646143Y213042D01*
X646342Y214106D01*
X646742Y215038D01*
X647341Y215570D01*
X647939Y215703D01*
X648538Y215570D01*
X649137Y215038D01*
X649536Y214106D01*
X649636Y213042D01*
X649536Y211977D01*
X649137Y211045D01*
X648538Y210513D01*
X647939Y210380D01*
G01X654228Y215703D02*
Y211977D01*
X654627Y211045D01*
X655226Y210513D01*
X655924Y210380D01*
X656623Y210513D01*
X657222Y211045D01*
X657621Y211977D01*
G01Y210380D02*
Y215703D01*
G01X662512Y208384D02*
X663211Y207851D01*
X664009Y207718D01*
X664708Y207851D01*
X665307Y208517D01*
X665706Y209448D01*
Y215703D01*
G01Y214639D02*
X665307Y215171D01*
X664708Y215570D01*
X664009Y215703D01*
X663211Y215437D01*
X662712Y214905D01*
X662312Y213973D01*
X662113Y213042D01*
X662213Y212243D01*
X662612Y211311D01*
X663211Y210646D01*
X664009Y210380D01*
X664608Y210513D01*
X665307Y211045D01*
X665706Y211577D01*
G01X670198Y210380D02*
Y218365D01*
G01Y214506D02*
X670697Y215171D01*
X671196Y215570D01*
X671994Y215703D01*
X672593Y215570D01*
X673292Y215038D01*
X673591Y214239D01*
Y210380D01*
G01X678183D02*
Y215703D01*
G01Y214372D02*
X678582Y215038D01*
X679181Y215570D01*
X679979Y215703D01*
X680678Y215570D01*
X681277Y215038D01*
X681576Y214106D01*
Y210380D01*
G01X686367Y213973D02*
X689561D01*
X689262Y214905D01*
X688763Y215437D01*
X688064Y215703D01*
X687365Y215570D01*
X686766Y215171D01*
X686367Y214239D01*
X686168Y213441D01*
Y212642D01*
X686367Y211844D01*
X686866Y211045D01*
X687465Y210513D01*
X688164Y210380D01*
X688863Y210646D01*
X689561Y211444D01*
G01X694352Y211311D02*
X694851Y210779D01*
X695550Y210380D01*
X696149D01*
X696748Y210646D01*
X697147Y211045D01*
X697347Y211577D01*
X697247Y212376D01*
X696848Y212775D01*
X695051Y213574D01*
X694652Y214506D01*
X694851Y215171D01*
X695251Y215570D01*
X695849Y215703D01*
X696448Y215570D01*
X697047Y215171D01*
G01X702337Y211311D02*
X702836Y210779D01*
X703535Y210380D01*
X704134D01*
X704733Y210646D01*
X705132Y211045D01*
X705332Y211577D01*
X705232Y212376D01*
X704833Y212775D01*
X703036Y213574D01*
X702637Y214506D01*
X702836Y215171D01*
X703236Y215570D01*
X703834Y215703D01*
X704433Y215570D01*
X705032Y215171D01*
G01X634358Y277380D02*
Y285365D01*
G01X638551D02*
Y277380D01*
G01Y281372D02*
X634358D01*
G01X644439Y277380D02*
X643841Y277513D01*
X643242Y278045D01*
X642842Y278977D01*
X642643Y280042D01*
X642842Y281106D01*
X643242Y282038D01*
X643841Y282570D01*
X644439Y282703D01*
X645038Y282570D01*
X645637Y282038D01*
X646036Y281106D01*
X646136Y280042D01*
X646036Y278977D01*
X645637Y278045D01*
X645038Y277513D01*
X644439Y277380D01*
G01X652424D02*
Y285365D01*
G01X658912Y280973D02*
X662106D01*
X661807Y281905D01*
X661308Y282437D01*
X660609Y282703D01*
X659910Y282570D01*
X659311Y282171D01*
X658912Y281239D01*
X658713Y280441D01*
Y279642D01*
X658912Y278844D01*
X659411Y278045D01*
X660010Y277513D01*
X660709Y277380D01*
X661408Y277646D01*
X662106Y278444D01*
G01X630087Y347380D02*
Y355365D01*
G01X634280D02*
Y347380D01*
G01Y351372D02*
X630087D01*
G01X640168Y347380D02*
X639570Y347513D01*
X638971Y348045D01*
X638571Y348977D01*
X638372Y350042D01*
X638571Y351106D01*
X638971Y352038D01*
X639570Y352570D01*
X640168Y352703D01*
X640767Y352570D01*
X641366Y352038D01*
X641765Y351106D01*
X641865Y350042D01*
X641765Y348977D01*
X641366Y348045D01*
X640767Y347513D01*
X640168Y347380D01*
G01X648153D02*
Y355365D01*
G01X654641Y350973D02*
X657835D01*
X657536Y351905D01*
X657037Y352437D01*
X656338Y352703D01*
X655639Y352570D01*
X655040Y352171D01*
X654641Y351239D01*
X654442Y350441D01*
Y349642D01*
X654641Y348844D01*
X655140Y348045D01*
X655739Y347513D01*
X656438Y347380D01*
X657137Y347646D01*
X657835Y348444D01*
G01X653254Y107765D02*
Y99780D01*
G01X650959Y107765D02*
X655550D01*
G01X659543Y99780D02*
Y107765D01*
G01Y103906D02*
X660042Y104571D01*
X660541Y104970D01*
X661339Y105103D01*
X661938Y104970D01*
X662637Y104438D01*
X662936Y103639D01*
Y99780D01*
G01X667727Y103373D02*
X670921D01*
X670622Y104305D01*
X670123Y104837D01*
X669424Y105103D01*
X668725Y104970D01*
X668126Y104571D01*
X667727Y103639D01*
X667528Y102841D01*
Y102042D01*
X667727Y101244D01*
X668226Y100445D01*
X668825Y99913D01*
X669524Y99780D01*
X670223Y100046D01*
X670921Y100844D01*
G01X675812Y99780D02*
Y105103D01*
G01Y104039D02*
X676311Y104571D01*
X676810Y104970D01*
X677509Y105103D01*
X678008Y104970D01*
X678607Y104571D01*
G01X683697Y103373D02*
X686891D01*
X686592Y104305D01*
X686093Y104837D01*
X685394Y105103D01*
X684695Y104970D01*
X684096Y104571D01*
X683697Y103639D01*
X683498Y102841D01*
Y102042D01*
X683697Y101244D01*
X684196Y100445D01*
X684795Y99913D01*
X685494Y99780D01*
X686193Y100046D01*
X686891Y100844D01*
G01X692581Y99780D02*
Y106567D01*
X692780Y107233D01*
X693179Y107632D01*
X693778Y107765D01*
X694377Y107499D01*
X694677Y106833D01*
G01X693479Y104571D02*
X691483D01*
G01X701164Y99780D02*
X700566Y99913D01*
X699967Y100445D01*
X699567Y101377D01*
X699368Y102442D01*
X699567Y103506D01*
X699967Y104438D01*
X700566Y104970D01*
X701164Y105103D01*
X701763Y104970D01*
X702362Y104438D01*
X702761Y103506D01*
X702861Y102442D01*
X702761Y101377D01*
X702362Y100445D01*
X701763Y99913D01*
X701164Y99780D01*
G01X707752D02*
Y105103D01*
G01Y104039D02*
X708251Y104571D01*
X708750Y104970D01*
X709449Y105103D01*
X709948Y104970D01*
X710547Y104571D01*
G01X715637Y103373D02*
X718831D01*
X718532Y104305D01*
X718033Y104837D01*
X717334Y105103D01*
X716635Y104970D01*
X716036Y104571D01*
X715637Y103639D01*
X715438Y102841D01*
Y102042D01*
X715637Y101244D01*
X716136Y100445D01*
X716735Y99913D01*
X717434Y99780D01*
X718133Y100046D01*
X718831Y100844D01*
G01X724920Y98316D02*
X725319Y100046D01*
G01X739293Y97118D02*
Y105103D01*
G01Y103906D02*
X739792Y104571D01*
X740291Y104970D01*
X741089Y105103D01*
X741788Y104970D01*
X742487Y104305D01*
X742786Y103373D01*
X742886Y102442D01*
X742786Y101510D01*
X742487Y100578D01*
X741888Y100046D01*
X741089Y99780D01*
X740391Y99913D01*
X739692Y100312D01*
X739293Y100844D01*
G01X749074Y99780D02*
Y107765D01*
G01X755562Y103373D02*
X758756D01*
X758457Y104305D01*
X757958Y104837D01*
X757259Y105103D01*
X756560Y104970D01*
X755961Y104571D01*
X755562Y103639D01*
X755363Y102841D01*
Y102042D01*
X755562Y101244D01*
X756061Y100445D01*
X756660Y99913D01*
X757359Y99780D01*
X758058Y100046D01*
X758756Y100844D01*
G01X766841Y99780D02*
Y105103D01*
G01Y104172D02*
X766442Y104704D01*
X765843Y104970D01*
X765144Y105103D01*
X764446Y104837D01*
X763847Y104305D01*
X763447Y103506D01*
X763248Y102442D01*
X763447Y101377D01*
X763847Y100578D01*
X764446Y100046D01*
X765144Y99780D01*
X765843Y99913D01*
X766442Y100312D01*
X766841Y100844D01*
G01X771532Y100711D02*
X772031Y100179D01*
X772730Y99780D01*
X773329D01*
X773928Y100046D01*
X774327Y100445D01*
X774527Y100977D01*
X774427Y101776D01*
X774028Y102175D01*
X772231Y102974D01*
X771832Y103906D01*
X772031Y104571D01*
X772431Y104970D01*
X773029Y105103D01*
X773628Y104970D01*
X774227Y104571D01*
G01X779517Y103373D02*
X782711D01*
X782412Y104305D01*
X781913Y104837D01*
X781214Y105103D01*
X780515Y104970D01*
X779916Y104571D01*
X779517Y103639D01*
X779318Y102841D01*
Y102042D01*
X779517Y101244D01*
X780016Y100445D01*
X780615Y99913D01*
X781314Y99780D01*
X782013Y100046D01*
X782711Y100844D01*
G01X796386Y99780D02*
Y106567D01*
X796585Y107233D01*
X796984Y107632D01*
X797583Y107765D01*
X798182Y107499D01*
X798482Y106833D01*
G01X797284Y104571D02*
X795288D01*
G01X804969Y99780D02*
X804371Y99913D01*
X803772Y100445D01*
X803372Y101377D01*
X803173Y102442D01*
X803372Y103506D01*
X803772Y104438D01*
X804371Y104970D01*
X804969Y105103D01*
X805568Y104970D01*
X806167Y104438D01*
X806566Y103506D01*
X806666Y102442D01*
X806566Y101377D01*
X806167Y100445D01*
X805568Y99913D01*
X804969Y99780D01*
G01X812954D02*
Y107765D01*
G01X820939Y99780D02*
Y107765D01*
G01X828924Y99780D02*
X828326Y99913D01*
X827727Y100445D01*
X827327Y101377D01*
X827128Y102442D01*
X827327Y103506D01*
X827727Y104438D01*
X828326Y104970D01*
X828924Y105103D01*
X829523Y104970D01*
X830122Y104438D01*
X830521Y103506D01*
X830621Y102442D01*
X830521Y101377D01*
X830122Y100445D01*
X829523Y99913D01*
X828924Y99780D01*
G01X834414Y105103D02*
X835612Y99780D01*
X836909Y105103D01*
X838207Y99780D01*
X839405Y105103D01*
G01X850684Y101377D02*
X851282Y100445D01*
X852081Y99913D01*
X852979Y99780D01*
X853778Y99913D01*
X854576Y100578D01*
X855075Y101377D01*
X855175Y102175D01*
X854976Y103107D01*
X854277Y103772D01*
X853578Y104039D01*
X852680D01*
G01X853578D02*
X854177Y104438D01*
X854676Y105103D01*
X854876Y105902D01*
X854676Y106700D01*
X854177Y107366D01*
X853279Y107765D01*
X852380Y107632D01*
X851482Y107099D01*
G01X860864Y99514D02*
X860665Y99647D01*
Y99913D01*
X860864Y100046D01*
X861064Y99913D01*
Y99647D01*
X860864Y99514D01*
G01X868849Y99780D02*
Y107765D01*
X867652Y106168D01*
G01Y99780D02*
X870047D01*
G01X876834D02*
X877533Y99913D01*
X878332Y100312D01*
X878831Y100977D01*
X879030Y101909D01*
X878831Y102841D01*
X878232Y103639D01*
X877334Y104039D01*
X876335D01*
X875736Y104305D01*
X875237Y104970D01*
X875038Y105902D01*
X875337Y106833D01*
X876036Y107499D01*
X876834Y107765D01*
X877633Y107499D01*
X878332Y106833D01*
X878631Y105902D01*
X878431Y104970D01*
X877933Y104305D01*
X877334Y104039D01*
X876335D01*
X875437Y103639D01*
X874838Y102841D01*
X874639Y101909D01*
X874838Y100977D01*
X875337Y100312D01*
X876136Y99913D01*
X876834Y99780D01*
G01X881825D02*
Y105103D01*
G01Y103639D02*
X882124Y104305D01*
X882624Y104837D01*
X883322Y105103D01*
X884021Y104837D01*
X884520Y104305D01*
X884819Y103639D01*
Y99780D01*
G01Y103639D02*
X885119Y104305D01*
X885618Y104837D01*
X886317Y105103D01*
X887015Y104837D01*
X887515Y104305D01*
X887814Y103506D01*
Y99780D01*
G01X889810D02*
Y105103D01*
G01Y103639D02*
X890109Y104305D01*
X890609Y104837D01*
X891307Y105103D01*
X892006Y104837D01*
X892505Y104305D01*
X892804Y103639D01*
Y99780D01*
G01Y103639D02*
X893104Y104305D01*
X893603Y104837D01*
X894302Y105103D01*
X895000Y104837D01*
X895500Y104305D01*
X895799Y103506D01*
Y99780D01*
G01X908774Y107765D02*
Y99780D01*
G01X907377Y105103D02*
X910172D01*
G01X916759Y99780D02*
X916161Y99913D01*
X915562Y100445D01*
X915162Y101377D01*
X914963Y102442D01*
X915162Y103506D01*
X915562Y104438D01*
X916161Y104970D01*
X916759Y105103D01*
X917358Y104970D01*
X917957Y104438D01*
X918356Y103506D01*
X918456Y102442D01*
X918356Y101377D01*
X917957Y100445D01*
X917358Y99913D01*
X916759Y99780D01*
G01X930933Y97118D02*
Y105103D01*
G01Y103906D02*
X931432Y104571D01*
X931931Y104970D01*
X932729Y105103D01*
X933428Y104970D01*
X934127Y104305D01*
X934426Y103373D01*
X934526Y102442D01*
X934426Y101510D01*
X934127Y100578D01*
X933528Y100046D01*
X932729Y99780D01*
X932031Y99913D01*
X931332Y100312D01*
X930933Y100844D01*
G01X939317Y99780D02*
Y105103D01*
G01Y104039D02*
X939816Y104571D01*
X940315Y104970D01*
X941014Y105103D01*
X941513Y104970D01*
X942112Y104571D01*
G01X948699Y99780D02*
X948101Y99913D01*
X947502Y100445D01*
X947102Y101377D01*
X946903Y102442D01*
X947102Y103506D01*
X947502Y104438D01*
X948101Y104970D01*
X948699Y105103D01*
X949298Y104970D01*
X949897Y104438D01*
X950296Y103506D01*
X950396Y102442D01*
X950296Y101377D01*
X949897Y100445D01*
X949298Y99913D01*
X948699Y99780D01*
G01X958481Y107765D02*
Y99780D01*
G01Y100977D02*
X958082Y100312D01*
X957483Y99913D01*
X956784Y99780D01*
X955986Y100046D01*
X955387Y100711D01*
X954988Y101510D01*
X954888Y102442D01*
X954988Y103373D01*
X955387Y104172D01*
X955986Y104837D01*
X956784Y105103D01*
X957483Y104970D01*
X957982Y104704D01*
X958481Y104172D01*
G01X962973Y105103D02*
Y101377D01*
X963372Y100445D01*
X963971Y99913D01*
X964669Y99780D01*
X965368Y99913D01*
X965967Y100445D01*
X966366Y101377D01*
G01Y99780D02*
Y105103D01*
G01X974251Y104438D02*
X973553Y104970D01*
X972954Y105103D01*
X972155Y104837D01*
X971556Y104305D01*
X971157Y103373D01*
X971057Y102442D01*
X971157Y101510D01*
X971556Y100711D01*
X972155Y100046D01*
X972954Y99780D01*
X973653Y100046D01*
X974251Y100578D01*
G01X979142Y103373D02*
X982336D01*
X982037Y104305D01*
X981538Y104837D01*
X980839Y105103D01*
X980140Y104970D01*
X979541Y104571D01*
X979142Y103639D01*
X978943Y102841D01*
Y102042D01*
X979142Y101244D01*
X979641Y100445D01*
X980240Y99913D01*
X980939Y99780D01*
X981638Y100046D01*
X982336Y100844D01*
G01X996609Y107765D02*
Y99780D01*
G01X995212Y105103D02*
X998007D01*
G01X1002898Y99780D02*
Y107765D01*
G01Y103906D02*
X1003397Y104571D01*
X1003896Y104970D01*
X1004694Y105103D01*
X1005293Y104970D01*
X1005992Y104438D01*
X1006291Y103639D01*
Y99780D01*
G01X1012579Y105103D02*
Y99780D01*
G01Y107233D02*
X1012380Y107366D01*
Y107632D01*
X1012579Y107765D01*
X1012779Y107632D01*
Y107366D01*
X1012579Y107233D01*
G01X1019067Y100711D02*
X1019566Y100179D01*
X1020265Y99780D01*
X1020864D01*
X1021463Y100046D01*
X1021862Y100445D01*
X1022062Y100977D01*
X1021962Y101776D01*
X1021563Y102175D01*
X1019766Y102974D01*
X1019367Y103906D01*
X1019566Y104571D01*
X1019966Y104970D01*
X1020564Y105103D01*
X1021163Y104970D01*
X1021762Y104571D01*
G01X1034738Y99780D02*
Y107765D01*
G01Y103772D02*
X1035237Y104571D01*
X1035836Y104970D01*
X1036435Y105103D01*
X1037333Y104837D01*
X1037932Y104305D01*
X1038331Y103373D01*
Y102309D01*
X1038131Y101244D01*
X1037732Y100445D01*
X1037034Y99913D01*
X1036435Y99780D01*
X1035836Y99913D01*
X1035237Y100312D01*
X1034738Y100977D01*
G01X1044519Y99780D02*
X1043921Y99913D01*
X1043322Y100445D01*
X1042922Y101377D01*
X1042723Y102442D01*
X1042922Y103506D01*
X1043322Y104438D01*
X1043921Y104970D01*
X1044519Y105103D01*
X1045118Y104970D01*
X1045717Y104438D01*
X1046116Y103506D01*
X1046216Y102442D01*
X1046116Y101377D01*
X1045717Y100445D01*
X1045118Y99913D01*
X1044519Y99780D01*
G01X1054301D02*
Y105103D01*
G01Y104172D02*
X1053902Y104704D01*
X1053303Y104970D01*
X1052604Y105103D01*
X1051906Y104837D01*
X1051307Y104305D01*
X1050907Y103506D01*
X1050708Y102442D01*
X1050907Y101377D01*
X1051307Y100578D01*
X1051906Y100046D01*
X1052604Y99780D01*
X1053303Y99913D01*
X1053902Y100312D01*
X1054301Y100844D01*
G01X1059092Y99780D02*
Y105103D01*
G01Y104039D02*
X1059591Y104571D01*
X1060090Y104970D01*
X1060789Y105103D01*
X1061288Y104970D01*
X1061887Y104571D01*
G01X1070271Y107765D02*
Y99780D01*
G01Y100977D02*
X1069872Y100312D01*
X1069273Y99913D01*
X1068574Y99780D01*
X1067776Y100046D01*
X1067177Y100711D01*
X1066778Y101510D01*
X1066678Y102442D01*
X1066778Y103373D01*
X1067177Y104172D01*
X1067776Y104837D01*
X1068574Y105103D01*
X1069273Y104970D01*
X1069772Y104704D01*
X1070271Y104172D01*
G01X1076459Y99514D02*
X1076260Y99647D01*
Y99913D01*
X1076459Y100046D01*
X1076659Y99913D01*
Y99647D01*
X1076459Y99514D01*
G01X653054Y117765D02*
Y109780D01*
G01X650759Y117765D02*
X655350D01*
G01X659343Y109780D02*
Y117765D01*
G01Y113906D02*
X659842Y114571D01*
X660341Y114970D01*
X661139Y115103D01*
X661738Y114970D01*
X662437Y114438D01*
X662736Y113639D01*
Y109780D01*
G01X667527Y113373D02*
X670721D01*
X670422Y114305D01*
X669923Y114837D01*
X669224Y115103D01*
X668525Y114970D01*
X667926Y114571D01*
X667527Y113639D01*
X667328Y112841D01*
Y112042D01*
X667527Y111244D01*
X668026Y110445D01*
X668625Y109913D01*
X669324Y109780D01*
X670023Y110046D01*
X670721Y110844D01*
G01X675313Y109780D02*
Y115103D01*
G01Y113772D02*
X675712Y114438D01*
X676311Y114970D01*
X677109Y115103D01*
X677808Y114970D01*
X678407Y114438D01*
X678706Y113506D01*
Y109780D01*
G01X694576Y114438D02*
X693878Y114970D01*
X693279Y115103D01*
X692480Y114837D01*
X691881Y114305D01*
X691482Y113373D01*
X691382Y112442D01*
X691482Y111510D01*
X691881Y110711D01*
X692480Y110046D01*
X693279Y109780D01*
X693978Y110046D01*
X694576Y110578D01*
G01X700964Y109780D02*
X700366Y109913D01*
X699767Y110445D01*
X699367Y111377D01*
X699168Y112442D01*
X699367Y113506D01*
X699767Y114438D01*
X700366Y114970D01*
X700964Y115103D01*
X701563Y114970D01*
X702162Y114438D01*
X702561Y113506D01*
X702661Y112442D01*
X702561Y111377D01*
X702162Y110445D01*
X701563Y109913D01*
X700964Y109780D01*
G01X707253D02*
Y115103D01*
G01Y113772D02*
X707652Y114438D01*
X708251Y114970D01*
X709049Y115103D01*
X709748Y114970D01*
X710347Y114438D01*
X710646Y113506D01*
Y109780D01*
G01X715138Y115103D02*
X716934Y109780D01*
X718731Y115103D01*
G01X723422Y113373D02*
X726616D01*
X726317Y114305D01*
X725818Y114837D01*
X725119Y115103D01*
X724420Y114970D01*
X723821Y114571D01*
X723422Y113639D01*
X723223Y112841D01*
Y112042D01*
X723422Y111244D01*
X723921Y110445D01*
X724520Y109913D01*
X725219Y109780D01*
X725918Y110046D01*
X726616Y110844D01*
G01X731507Y109780D02*
Y115103D01*
G01Y114039D02*
X732006Y114571D01*
X732505Y114970D01*
X733204Y115103D01*
X733703Y114970D01*
X734302Y114571D01*
G01X740889Y117765D02*
Y109780D01*
G01X739492Y115103D02*
X742287D01*
G01X754664Y111377D02*
X755262Y110445D01*
X756061Y109913D01*
X756959Y109780D01*
X757758Y109913D01*
X758556Y110578D01*
X759055Y111377D01*
X759155Y112175D01*
X758956Y113107D01*
X758257Y113772D01*
X757558Y114039D01*
X756660D01*
G01X757558D02*
X758157Y114438D01*
X758656Y115103D01*
X758856Y115902D01*
X758656Y116700D01*
X758157Y117366D01*
X757259Y117765D01*
X756360Y117632D01*
X755462Y117099D01*
G01X764844Y109514D02*
X764645Y109647D01*
Y109913D01*
X764844Y110046D01*
X765044Y109913D01*
Y109647D01*
X764844Y109514D01*
G01X772829Y109780D02*
Y117765D01*
X771632Y116168D01*
G01Y109780D02*
X774027D01*
G01X780814D02*
X781513Y109913D01*
X782312Y110312D01*
X782811Y110977D01*
X783010Y111909D01*
X782811Y112841D01*
X782212Y113639D01*
X781314Y114039D01*
X780315D01*
X779716Y114305D01*
X779217Y114970D01*
X779018Y115902D01*
X779317Y116833D01*
X780016Y117499D01*
X780814Y117765D01*
X781613Y117499D01*
X782312Y116833D01*
X782611Y115902D01*
X782411Y114970D01*
X781913Y114305D01*
X781314Y114039D01*
X780315D01*
X779417Y113639D01*
X778818Y112841D01*
X778619Y111909D01*
X778818Y110977D01*
X779317Y110312D01*
X780116Y109913D01*
X780814Y109780D01*
G01X785805D02*
Y115103D01*
G01Y113639D02*
X786104Y114305D01*
X786604Y114837D01*
X787302Y115103D01*
X788001Y114837D01*
X788500Y114305D01*
X788799Y113639D01*
Y109780D01*
G01Y113639D02*
X789099Y114305D01*
X789598Y114837D01*
X790297Y115103D01*
X790995Y114837D01*
X791495Y114305D01*
X791794Y113506D01*
Y109780D01*
G01X793790D02*
Y115103D01*
G01Y113639D02*
X794089Y114305D01*
X794589Y114837D01*
X795287Y115103D01*
X795986Y114837D01*
X796485Y114305D01*
X796784Y113639D01*
Y109780D01*
G01Y113639D02*
X797084Y114305D01*
X797583Y114837D01*
X798282Y115103D01*
X798980Y114837D01*
X799480Y114305D01*
X799779Y113506D01*
Y109780D01*
G01X812754Y115103D02*
Y109780D01*
G01Y117233D02*
X812555Y117366D01*
Y117632D01*
X812754Y117765D01*
X812954Y117632D01*
Y117366D01*
X812754Y117233D01*
G01X819043Y109780D02*
Y115103D01*
G01Y113772D02*
X819442Y114438D01*
X820041Y114970D01*
X820839Y115103D01*
X821538Y114970D01*
X822137Y114438D01*
X822436Y113506D01*
Y109780D01*
G01X828724Y117765D02*
Y109780D01*
G01X827327Y115103D02*
X830122D01*
G01X836709Y109780D02*
X836111Y109913D01*
X835512Y110445D01*
X835112Y111377D01*
X834913Y112442D01*
X835112Y113506D01*
X835512Y114438D01*
X836111Y114970D01*
X836709Y115103D01*
X837308Y114970D01*
X837907Y114438D01*
X838306Y113506D01*
X838406Y112442D01*
X838306Y111377D01*
X837907Y110445D01*
X837308Y109913D01*
X836709Y109780D01*
G01X852679D02*
Y117765D01*
X851482Y116168D01*
G01Y109780D02*
X853877D01*
G01X858768Y116434D02*
X859367Y117233D01*
X860066Y117632D01*
X860864Y117765D01*
X861862Y117499D01*
X862561Y116833D01*
X862761Y116035D01*
X862661Y115236D01*
X862261Y114571D01*
X860265Y113240D01*
X859367Y112309D01*
X858768Y110977D01*
X858568Y109780D01*
X862761D01*
G01X866454Y110977D02*
X867052Y110312D01*
X867751Y109913D01*
X868649Y109780D01*
X869548Y110046D01*
X870246Y110578D01*
X870746Y111510D01*
X870845Y112575D01*
X870646Y113639D01*
X870147Y114305D01*
X869448Y114837D01*
X868749Y114970D01*
X868051Y114837D01*
X867152Y114305D01*
X867452Y117765D01*
X870147D01*
G01X876634Y109514D02*
X876435Y109647D01*
Y109913D01*
X876634Y110046D01*
X876834Y109913D01*
Y109647D01*
X876634Y109514D01*
G01X884619Y109780D02*
Y117765D01*
X883422Y116168D01*
G01Y109780D02*
X885817D01*
G01X890908Y110711D02*
X891606Y110046D01*
X892405Y109780D01*
X893203Y110046D01*
X893902Y110844D01*
X894401Y112042D01*
X894601Y113240D01*
Y114704D01*
X894401Y115902D01*
X893902Y116966D01*
X893303Y117499D01*
X892604Y117765D01*
X891806Y117499D01*
X891207Y116966D01*
X890808Y116168D01*
X890608Y115103D01*
X890808Y114172D01*
X891307Y113240D01*
X891906Y112708D01*
X892604Y112575D01*
X893403Y112841D01*
X894002Y113506D01*
X894601Y114704D01*
G01X898693Y113107D02*
X899392Y114039D01*
X899991Y114571D01*
X900789Y114837D01*
X901488Y114571D01*
X901987Y114039D01*
X902386Y113240D01*
X902486Y112309D01*
X902386Y111510D01*
X901987Y110711D01*
X901388Y110046D01*
X900689Y109780D01*
X899891Y110046D01*
X899192Y110844D01*
X898793Y112042D01*
X898693Y113373D01*
X898893Y115103D01*
X899192Y116035D01*
X899691Y116966D01*
X900390Y117632D01*
X901089Y117765D01*
X901787Y117499D01*
X902286Y116833D01*
G01X908574Y109780D02*
X909273Y109913D01*
X910072Y110312D01*
X910571Y110977D01*
X910770Y111909D01*
X910571Y112841D01*
X909972Y113639D01*
X909074Y114039D01*
X908075D01*
X907476Y114305D01*
X906977Y114970D01*
X906778Y115902D01*
X907077Y116833D01*
X907776Y117499D01*
X908574Y117765D01*
X909373Y117499D01*
X910072Y116833D01*
X910371Y115902D01*
X910171Y114970D01*
X909673Y114305D01*
X909074Y114039D01*
X908075D01*
X907177Y113639D01*
X906578Y112841D01*
X906379Y111909D01*
X906578Y110977D01*
X907077Y110312D01*
X907876Y109913D01*
X908574Y109780D01*
G01X913565D02*
Y115103D01*
G01Y113639D02*
X913864Y114305D01*
X914364Y114837D01*
X915062Y115103D01*
X915761Y114837D01*
X916260Y114305D01*
X916559Y113639D01*
Y109780D01*
G01Y113639D02*
X916859Y114305D01*
X917358Y114837D01*
X918057Y115103D01*
X918755Y114837D01*
X919255Y114305D01*
X919554Y113506D01*
Y109780D01*
G01X924544Y115103D02*
Y109780D01*
G01Y117233D02*
X924345Y117366D01*
Y117632D01*
X924544Y117765D01*
X924744Y117632D01*
Y117366D01*
X924544Y117233D01*
G01X932529Y109780D02*
Y117765D01*
G01X940315Y108316D02*
X940714Y110046D01*
G01X956484Y117765D02*
Y109780D01*
G01X955087Y115103D02*
X957882D01*
G01X962773Y109780D02*
Y117765D01*
G01Y113906D02*
X963272Y114571D01*
X963771Y114970D01*
X964569Y115103D01*
X965168Y114970D01*
X965867Y114438D01*
X966166Y113639D01*
Y109780D01*
G01X970957Y113373D02*
X974151D01*
X973852Y114305D01*
X973353Y114837D01*
X972654Y115103D01*
X971955Y114970D01*
X971356Y114571D01*
X970957Y113639D01*
X970758Y112841D01*
Y112042D01*
X970957Y111244D01*
X971456Y110445D01*
X972055Y109913D01*
X972754Y109780D01*
X973453Y110046D01*
X974151Y110844D01*
G01X990221Y117765D02*
Y109780D01*
G01Y110977D02*
X989822Y110312D01*
X989223Y109913D01*
X988524Y109780D01*
X987726Y110046D01*
X987127Y110711D01*
X986728Y111510D01*
X986628Y112442D01*
X986728Y113373D01*
X987127Y114172D01*
X987726Y114837D01*
X988524Y115103D01*
X989223Y114970D01*
X989722Y114704D01*
X990221Y114172D01*
G01X996409Y115103D02*
Y109780D01*
G01Y117233D02*
X996210Y117366D01*
Y117632D01*
X996409Y117765D01*
X996609Y117632D01*
Y117366D01*
X996409Y117233D01*
G01X1003796Y109780D02*
Y116567D01*
X1003995Y117233D01*
X1004394Y117632D01*
X1004993Y117765D01*
X1005592Y117499D01*
X1005892Y116833D01*
G01X1004694Y114571D02*
X1002698D01*
G01X1011781Y109780D02*
Y116567D01*
X1011980Y117233D01*
X1012379Y117632D01*
X1012978Y117765D01*
X1013577Y117499D01*
X1013877Y116833D01*
G01X1012679Y114571D02*
X1010683D01*
G01X1018867Y113373D02*
X1022061D01*
X1021762Y114305D01*
X1021263Y114837D01*
X1020564Y115103D01*
X1019865Y114970D01*
X1019266Y114571D01*
X1018867Y113639D01*
X1018668Y112841D01*
Y112042D01*
X1018867Y111244D01*
X1019366Y110445D01*
X1019965Y109913D01*
X1020664Y109780D01*
X1021363Y110046D01*
X1022061Y110844D01*
G01X1026952Y109780D02*
Y115103D01*
G01Y114039D02*
X1027451Y114571D01*
X1027950Y114970D01*
X1028649Y115103D01*
X1029148Y114970D01*
X1029747Y114571D01*
G01X1034837Y113373D02*
X1038031D01*
X1037732Y114305D01*
X1037233Y114837D01*
X1036534Y115103D01*
X1035835Y114970D01*
X1035236Y114571D01*
X1034837Y113639D01*
X1034638Y112841D01*
Y112042D01*
X1034837Y111244D01*
X1035336Y110445D01*
X1035935Y109913D01*
X1036634Y109780D01*
X1037333Y110046D01*
X1038031Y110844D01*
G01X1042623Y109780D02*
Y115103D01*
G01Y113772D02*
X1043022Y114438D01*
X1043621Y114970D01*
X1044419Y115103D01*
X1045118Y114970D01*
X1045717Y114438D01*
X1046016Y113506D01*
Y109780D01*
G01X1053901Y114438D02*
X1053203Y114970D01*
X1052604Y115103D01*
X1051805Y114837D01*
X1051206Y114305D01*
X1050807Y113373D01*
X1050707Y112442D01*
X1050807Y111510D01*
X1051206Y110711D01*
X1051805Y110046D01*
X1052604Y109780D01*
X1053303Y110046D01*
X1053901Y110578D01*
G01X1058792Y113373D02*
X1061986D01*
X1061687Y114305D01*
X1061188Y114837D01*
X1060489Y115103D01*
X1059790Y114970D01*
X1059191Y114571D01*
X1058792Y113639D01*
X1058593Y112841D01*
Y112042D01*
X1058792Y111244D01*
X1059291Y110445D01*
X1059890Y109913D01*
X1060589Y109780D01*
X1061288Y110046D01*
X1061986Y110844D01*
G01X1074463Y109780D02*
Y117765D01*
G01Y113772D02*
X1074962Y114571D01*
X1075561Y114970D01*
X1076160Y115103D01*
X1077058Y114837D01*
X1077657Y114305D01*
X1078056Y113373D01*
Y112309D01*
X1077856Y111244D01*
X1077457Y110445D01*
X1076759Y109913D01*
X1076160Y109780D01*
X1075561Y109913D01*
X1074962Y110312D01*
X1074463Y110977D01*
G01X1082747Y113373D02*
X1085941D01*
X1085642Y114305D01*
X1085143Y114837D01*
X1084444Y115103D01*
X1083745Y114970D01*
X1083146Y114571D01*
X1082747Y113639D01*
X1082548Y112841D01*
Y112042D01*
X1082747Y111244D01*
X1083246Y110445D01*
X1083845Y109913D01*
X1084544Y109780D01*
X1085243Y110046D01*
X1085941Y110844D01*
G01X1092229Y117765D02*
Y109780D01*
G01X1090832Y115103D02*
X1093627D01*
G01X1097719D02*
X1098917Y109780D01*
X1100214Y115103D01*
X1101512Y109780D01*
X1102710Y115103D01*
G01X1106702Y113373D02*
X1109896D01*
X1109597Y114305D01*
X1109098Y114837D01*
X1108399Y115103D01*
X1107700Y114970D01*
X1107101Y114571D01*
X1106702Y113639D01*
X1106503Y112841D01*
Y112042D01*
X1106702Y111244D01*
X1107201Y110445D01*
X1107800Y109913D01*
X1108499Y109780D01*
X1109198Y110046D01*
X1109896Y110844D01*
G01X1114687Y113373D02*
X1117881D01*
X1117582Y114305D01*
X1117083Y114837D01*
X1116384Y115103D01*
X1115685Y114970D01*
X1115086Y114571D01*
X1114687Y113639D01*
X1114488Y112841D01*
Y112042D01*
X1114687Y111244D01*
X1115186Y110445D01*
X1115785Y109913D01*
X1116484Y109780D01*
X1117183Y110046D01*
X1117881Y110844D01*
G01X1122473Y109780D02*
Y115103D01*
G01Y113772D02*
X1122872Y114438D01*
X1123471Y114970D01*
X1124269Y115103D01*
X1124968Y114970D01*
X1125567Y114438D01*
X1125866Y113506D01*
Y109780D01*
G01X1140139D02*
Y117765D01*
X1138942Y116168D01*
G01Y109780D02*
X1141337D01*
G01X1146228Y116434D02*
X1146827Y117233D01*
X1147526Y117632D01*
X1148324Y117765D01*
X1149322Y117499D01*
X1150021Y116833D01*
X1150221Y116035D01*
X1150121Y115236D01*
X1149721Y114571D01*
X1147725Y113240D01*
X1146827Y112309D01*
X1146228Y110977D01*
X1146028Y109780D01*
X1150221D01*
G01X1154213Y113107D02*
X1154912Y114039D01*
X1155511Y114571D01*
X1156309Y114837D01*
X1157008Y114571D01*
X1157507Y114039D01*
X1157906Y113240D01*
X1158006Y112309D01*
X1157906Y111510D01*
X1157507Y110711D01*
X1156908Y110046D01*
X1156209Y109780D01*
X1155411Y110046D01*
X1154712Y110844D01*
X1154313Y112042D01*
X1154213Y113373D01*
X1154413Y115103D01*
X1154712Y116035D01*
X1155211Y116966D01*
X1155910Y117632D01*
X1156609Y117765D01*
X1157307Y117499D01*
X1157806Y116833D01*
G01X1161100Y109780D02*
Y115103D01*
G01Y113639D02*
X1161399Y114305D01*
X1161899Y114837D01*
X1162597Y115103D01*
X1163296Y114837D01*
X1163795Y114305D01*
X1164094Y113639D01*
Y109780D01*
G01Y113639D02*
X1164394Y114305D01*
X1164893Y114837D01*
X1165592Y115103D01*
X1166290Y114837D01*
X1166790Y114305D01*
X1167089Y113506D01*
Y109780D01*
G01X1172079Y115103D02*
Y109780D01*
G01Y117233D02*
X1171880Y117366D01*
Y117632D01*
X1172079Y117765D01*
X1172279Y117632D01*
Y117366D01*
X1172079Y117233D01*
G01X1180064Y109780D02*
Y117765D01*
G01X1197831Y109780D02*
Y115103D01*
G01Y114172D02*
X1197432Y114704D01*
X1196833Y114970D01*
X1196134Y115103D01*
X1195436Y114837D01*
X1194837Y114305D01*
X1194437Y113506D01*
X1194238Y112442D01*
X1194437Y111377D01*
X1194837Y110578D01*
X1195436Y110046D01*
X1196134Y109780D01*
X1196833Y109913D01*
X1197432Y110312D01*
X1197831Y110844D01*
G01X1202323Y109780D02*
Y115103D01*
G01Y113772D02*
X1202722Y114438D01*
X1203321Y114970D01*
X1204119Y115103D01*
X1204818Y114970D01*
X1205417Y114438D01*
X1205716Y113506D01*
Y109780D01*
G01X1213801Y117765D02*
Y109780D01*
G01Y110977D02*
X1213402Y110312D01*
X1212803Y109913D01*
X1212104Y109780D01*
X1211306Y110046D01*
X1210707Y110711D01*
X1210308Y111510D01*
X1210208Y112442D01*
X1210308Y113373D01*
X1210707Y114172D01*
X1211306Y114837D01*
X1212104Y115103D01*
X1212803Y114970D01*
X1213302Y114704D01*
X1213801Y114172D01*
G01X1227974Y109780D02*
Y117765D01*
X1226777Y116168D01*
G01Y109780D02*
X1229172D01*
G01X1234063Y116434D02*
X1234662Y117233D01*
X1235361Y117632D01*
X1236159Y117765D01*
X1237157Y117499D01*
X1237856Y116833D01*
X1238056Y116035D01*
X1237956Y115236D01*
X1237556Y114571D01*
X1235560Y113240D01*
X1234662Y112309D01*
X1234063Y110977D01*
X1233863Y109780D01*
X1238056D01*
G01X1241749Y110977D02*
X1242347Y110312D01*
X1243046Y109913D01*
X1243944Y109780D01*
X1244843Y110046D01*
X1245541Y110578D01*
X1246041Y111510D01*
X1246140Y112575D01*
X1245941Y113639D01*
X1245442Y114305D01*
X1244743Y114837D01*
X1244044Y114970D01*
X1243346Y114837D01*
X1242447Y114305D01*
X1242747Y117765D01*
X1245442D01*
G01X1251929Y109514D02*
X1251730Y109647D01*
Y109913D01*
X1251929Y110046D01*
X1252129Y109913D01*
Y109647D01*
X1251929Y109514D01*
G01X1259914Y109780D02*
Y117765D01*
X1258717Y116168D01*
G01Y109780D02*
X1261112D01*
G01X1266203Y110711D02*
X1266901Y110046D01*
X1267700Y109780D01*
X1268498Y110046D01*
X1269197Y110844D01*
X1269696Y112042D01*
X1269896Y113240D01*
Y114704D01*
X1269696Y115902D01*
X1269197Y116966D01*
X1268598Y117499D01*
X1267899Y117765D01*
X1267101Y117499D01*
X1266502Y116966D01*
X1266103Y116168D01*
X1265903Y115103D01*
X1266103Y114172D01*
X1266602Y113240D01*
X1267201Y112708D01*
X1267899Y112575D01*
X1268698Y112841D01*
X1269297Y113506D01*
X1269896Y114704D01*
G01X1273988Y113107D02*
X1274687Y114039D01*
X1275286Y114571D01*
X1276084Y114837D01*
X1276783Y114571D01*
X1277282Y114039D01*
X1277681Y113240D01*
X1277781Y112309D01*
X1277681Y111510D01*
X1277282Y110711D01*
X1276683Y110046D01*
X1275984Y109780D01*
X1275186Y110046D01*
X1274487Y110844D01*
X1274088Y112042D01*
X1273988Y113373D01*
X1274188Y115103D01*
X1274487Y116035D01*
X1274986Y116966D01*
X1275685Y117632D01*
X1276384Y117765D01*
X1277082Y117499D01*
X1277581Y116833D01*
G01X1283869Y109780D02*
X1284568Y109913D01*
X1285367Y110312D01*
X1285866Y110977D01*
X1286065Y111909D01*
X1285866Y112841D01*
X1285267Y113639D01*
X1284369Y114039D01*
X1283370D01*
X1282771Y114305D01*
X1282272Y114970D01*
X1282073Y115902D01*
X1282372Y116833D01*
X1283071Y117499D01*
X1283869Y117765D01*
X1284668Y117499D01*
X1285367Y116833D01*
X1285666Y115902D01*
X1285466Y114970D01*
X1284968Y114305D01*
X1284369Y114039D01*
X1283370D01*
X1282472Y113639D01*
X1281873Y112841D01*
X1281674Y111909D01*
X1281873Y110977D01*
X1282372Y110312D01*
X1283171Y109913D01*
X1283869Y109780D01*
G01X1299839Y115103D02*
Y109780D01*
G01Y117233D02*
X1299640Y117366D01*
Y117632D01*
X1299839Y117765D01*
X1300039Y117632D01*
Y117366D01*
X1299839Y117233D01*
G01X1306327Y110711D02*
X1306826Y110179D01*
X1307525Y109780D01*
X1308124D01*
X1308723Y110046D01*
X1309122Y110445D01*
X1309322Y110977D01*
X1309222Y111776D01*
X1308823Y112175D01*
X1307026Y112974D01*
X1306627Y113906D01*
X1306826Y114571D01*
X1307226Y114970D01*
X1307824Y115103D01*
X1308423Y114970D01*
X1309022Y114571D01*
G01X1323794Y109780D02*
Y117765D01*
G01X1330282Y113373D02*
X1333476D01*
X1333177Y114305D01*
X1332678Y114837D01*
X1331979Y115103D01*
X1331280Y114970D01*
X1330681Y114571D01*
X1330282Y113639D01*
X1330083Y112841D01*
Y112042D01*
X1330282Y111244D01*
X1330781Y110445D01*
X1331380Y109913D01*
X1332079Y109780D01*
X1332778Y110046D01*
X1333476Y110844D01*
G01X1338267Y110711D02*
X1338766Y110179D01*
X1339465Y109780D01*
X1340064D01*
X1340663Y110046D01*
X1341062Y110445D01*
X1341262Y110977D01*
X1341162Y111776D01*
X1340763Y112175D01*
X1338966Y112974D01*
X1338567Y113906D01*
X1338766Y114571D01*
X1339166Y114970D01*
X1339764Y115103D01*
X1340363Y114970D01*
X1340962Y114571D01*
G01X1346252Y110711D02*
X1346751Y110179D01*
X1347450Y109780D01*
X1348049D01*
X1348648Y110046D01*
X1349047Y110445D01*
X1349247Y110977D01*
X1349147Y111776D01*
X1348748Y112175D01*
X1346951Y112974D01*
X1346552Y113906D01*
X1346751Y114571D01*
X1347151Y114970D01*
X1347749Y115103D01*
X1348348Y114970D01*
X1348947Y114571D01*
G01X1363719Y117765D02*
Y109780D01*
G01X1362322Y115103D02*
X1365117D01*
G01X1370008Y109780D02*
Y117765D01*
G01Y113906D02*
X1370507Y114571D01*
X1371006Y114970D01*
X1371804Y115103D01*
X1372403Y114970D01*
X1373102Y114438D01*
X1373401Y113639D01*
Y109780D01*
G01X1381486D02*
Y115103D01*
G01Y114172D02*
X1381087Y114704D01*
X1380488Y114970D01*
X1379789Y115103D01*
X1379091Y114837D01*
X1378492Y114305D01*
X1378092Y113506D01*
X1377893Y112442D01*
X1378092Y111377D01*
X1378492Y110578D01*
X1379091Y110046D01*
X1379789Y109780D01*
X1380488Y109913D01*
X1381087Y110312D01*
X1381486Y110844D01*
G01X1385978Y109780D02*
Y115103D01*
G01Y113772D02*
X1386377Y114438D01*
X1386976Y114970D01*
X1387774Y115103D01*
X1388473Y114970D01*
X1389072Y114438D01*
X1389371Y113506D01*
Y109780D01*
G01X1403644D02*
Y117765D01*
X1402447Y116168D01*
G01Y109780D02*
X1404842D01*
G01X1416620D02*
Y115103D01*
G01Y113639D02*
X1416919Y114305D01*
X1417419Y114837D01*
X1418117Y115103D01*
X1418816Y114837D01*
X1419315Y114305D01*
X1419614Y113639D01*
Y109780D01*
G01Y113639D02*
X1419914Y114305D01*
X1420413Y114837D01*
X1421112Y115103D01*
X1421810Y114837D01*
X1422310Y114305D01*
X1422609Y113506D01*
Y109780D01*
G01X1427599Y115103D02*
Y109780D01*
G01Y117233D02*
X1427400Y117366D01*
Y117632D01*
X1427599Y117765D01*
X1427799Y117632D01*
Y117366D01*
X1427599Y117233D01*
G01X1435584Y109780D02*
Y117765D01*
G01X1443370Y108316D02*
X1443769Y110046D01*
G01X664688Y346880D02*
X667183Y354865D01*
X669679Y346880D01*
G01X668780Y349675D02*
X665586D01*
G01X675168Y346880D02*
Y354865D01*
G01X683153Y352203D02*
Y346880D01*
G01Y354333D02*
X682954Y354466D01*
Y354732D01*
X683153Y354865D01*
X683353Y354732D01*
Y354466D01*
X683153Y354333D01*
G01X689741Y344884D02*
X690440Y344351D01*
X691238Y344218D01*
X691937Y344351D01*
X692536Y345017D01*
X692935Y345948D01*
Y352203D01*
G01Y351139D02*
X692536Y351671D01*
X691937Y352070D01*
X691238Y352203D01*
X690440Y351937D01*
X689941Y351405D01*
X689541Y350473D01*
X689342Y349542D01*
X689442Y348743D01*
X689841Y347811D01*
X690440Y347146D01*
X691238Y346880D01*
X691837Y347013D01*
X692536Y347545D01*
X692935Y348077D01*
G01X697427Y346880D02*
Y352203D01*
G01Y350872D02*
X697826Y351538D01*
X698425Y352070D01*
X699223Y352203D01*
X699922Y352070D01*
X700521Y351538D01*
X700820Y350606D01*
Y346880D01*
G01X704114D02*
Y352203D01*
G01Y350739D02*
X704413Y351405D01*
X704913Y351937D01*
X705611Y352203D01*
X706310Y351937D01*
X706809Y351405D01*
X707108Y350739D01*
Y346880D01*
G01Y350739D02*
X707408Y351405D01*
X707907Y351937D01*
X708606Y352203D01*
X709304Y351937D01*
X709804Y351405D01*
X710103Y350606D01*
Y346880D01*
G01X713596Y350473D02*
X716790D01*
X716491Y351405D01*
X715992Y351937D01*
X715293Y352203D01*
X714594Y352070D01*
X713995Y351671D01*
X713596Y350739D01*
X713397Y349941D01*
Y349142D01*
X713596Y348344D01*
X714095Y347545D01*
X714694Y347013D01*
X715393Y346880D01*
X716092Y347146D01*
X716790Y347944D01*
G01X721382Y346880D02*
Y352203D01*
G01Y350872D02*
X721781Y351538D01*
X722380Y352070D01*
X723178Y352203D01*
X723877Y352070D01*
X724476Y351538D01*
X724775Y350606D01*
Y346880D01*
G01X731063Y354865D02*
Y346880D01*
G01X729666Y352203D02*
X732461D01*
G01X677358Y278444D02*
X678157Y277779D01*
X679055Y277380D01*
X679854D01*
X680652Y277779D01*
X681251Y278444D01*
X681551Y279376D01*
X681351Y280308D01*
X680852Y281106D01*
X679954Y281639D01*
X678756Y281905D01*
X678057Y282437D01*
X677758Y283369D01*
X677957Y284300D01*
X678456Y284966D01*
X679155Y285365D01*
X679854D01*
X680553Y285099D01*
X681151Y284433D01*
G01X687439Y282703D02*
Y277380D01*
G01Y284833D02*
X687240Y284966D01*
Y285232D01*
X687439Y285365D01*
X687639Y285232D01*
Y284966D01*
X687439Y284833D01*
G01X693927Y282703D02*
X696922D01*
X693927Y277380D01*
X696922D01*
G01X701912Y280973D02*
X705106D01*
X704807Y281905D01*
X704308Y282437D01*
X703609Y282703D01*
X702910Y282570D01*
X702311Y282171D01*
X701912Y281239D01*
X701713Y280441D01*
Y279642D01*
X701912Y278844D01*
X702411Y278045D01*
X703010Y277513D01*
X703709Y277380D01*
X704408Y277646D01*
X705106Y278444D01*
G01X739858Y210880D02*
Y218865D01*
G01X744051D02*
Y210880D01*
G01Y214872D02*
X739858D01*
G01X749939Y210880D02*
X749341Y211013D01*
X748742Y211545D01*
X748342Y212477D01*
X748143Y213542D01*
X748342Y214606D01*
X748742Y215538D01*
X749341Y216070D01*
X749939Y216203D01*
X750538Y216070D01*
X751137Y215538D01*
X751536Y214606D01*
X751636Y213542D01*
X751536Y212477D01*
X751137Y211545D01*
X750538Y211013D01*
X749939Y210880D01*
G01X757924D02*
Y218865D01*
G01X764412Y214473D02*
X767606D01*
X767307Y215405D01*
X766808Y215937D01*
X766109Y216203D01*
X765410Y216070D01*
X764811Y215671D01*
X764412Y214739D01*
X764213Y213941D01*
Y213142D01*
X764412Y212344D01*
X764911Y211545D01*
X765510Y211013D01*
X766209Y210880D01*
X766908Y211146D01*
X767606Y211944D01*
G01X778885Y218865D02*
X780282Y210880D01*
X781879Y218865D01*
X783476Y210880D01*
X784874Y218865D01*
G01X791661Y210880D02*
Y216203D01*
G01Y215272D02*
X791262Y215804D01*
X790663Y216070D01*
X789964Y216203D01*
X789266Y215937D01*
X788667Y215405D01*
X788267Y214606D01*
X788068Y213542D01*
X788267Y212477D01*
X788667Y211678D01*
X789266Y211146D01*
X789964Y210880D01*
X790663Y211013D01*
X791262Y211412D01*
X791661Y211944D01*
G01X797849Y210880D02*
Y218865D01*
G01X805834Y210880D02*
Y218865D01*
G01X819808Y210880D02*
Y218865D01*
X822304D01*
X823102Y218466D01*
X823601Y217933D01*
X823801Y216869D01*
X823601Y215804D01*
X823002Y215139D01*
X822304Y214739D01*
X819808D01*
G01X822304D02*
X823801Y210880D01*
G01X829789D02*
X829191Y211013D01*
X828592Y211545D01*
X828192Y212477D01*
X827993Y213542D01*
X828192Y214606D01*
X828592Y215538D01*
X829191Y216070D01*
X829789Y216203D01*
X830388Y216070D01*
X830987Y215538D01*
X831386Y214606D01*
X831486Y213542D01*
X831386Y212477D01*
X830987Y211545D01*
X830388Y211013D01*
X829789Y210880D01*
G01X836078Y216203D02*
Y212477D01*
X836477Y211545D01*
X837076Y211013D01*
X837774Y210880D01*
X838473Y211013D01*
X839072Y211545D01*
X839471Y212477D01*
G01Y210880D02*
Y216203D01*
G01X844362Y208884D02*
X845061Y208351D01*
X845859Y208218D01*
X846558Y208351D01*
X847157Y209017D01*
X847556Y209948D01*
Y216203D01*
G01Y215139D02*
X847157Y215671D01*
X846558Y216070D01*
X845859Y216203D01*
X845061Y215937D01*
X844562Y215405D01*
X844162Y214473D01*
X843963Y213542D01*
X844063Y212743D01*
X844462Y211811D01*
X845061Y211146D01*
X845859Y210880D01*
X846458Y211013D01*
X847157Y211545D01*
X847556Y212077D01*
G01X852048Y210880D02*
Y218865D01*
G01Y215006D02*
X852547Y215671D01*
X853046Y216070D01*
X853844Y216203D01*
X854443Y216070D01*
X855142Y215538D01*
X855441Y214739D01*
Y210880D01*
G01X860033D02*
Y216203D01*
G01Y214872D02*
X860432Y215538D01*
X861031Y216070D01*
X861829Y216203D01*
X862528Y216070D01*
X863127Y215538D01*
X863426Y214606D01*
Y210880D01*
G01X868217Y214473D02*
X871411D01*
X871112Y215405D01*
X870613Y215937D01*
X869914Y216203D01*
X869215Y216070D01*
X868616Y215671D01*
X868217Y214739D01*
X868018Y213941D01*
Y213142D01*
X868217Y212344D01*
X868716Y211545D01*
X869315Y211013D01*
X870014Y210880D01*
X870713Y211146D01*
X871411Y211944D01*
G01X876202Y211811D02*
X876701Y211279D01*
X877400Y210880D01*
X877999D01*
X878598Y211146D01*
X878997Y211545D01*
X879197Y212077D01*
X879097Y212876D01*
X878698Y213275D01*
X876901Y214074D01*
X876502Y215006D01*
X876701Y215671D01*
X877101Y216070D01*
X877699Y216203D01*
X878298Y216070D01*
X878897Y215671D01*
G01X884187Y211811D02*
X884686Y211279D01*
X885385Y210880D01*
X885984D01*
X886583Y211146D01*
X886982Y211545D01*
X887182Y212077D01*
X887082Y212876D01*
X886683Y213275D01*
X884886Y214074D01*
X884487Y215006D01*
X884686Y215671D01*
X885086Y216070D01*
X885684Y216203D01*
X886283Y216070D01*
X886882Y215671D01*
G01X740954Y222880D02*
X740156Y223013D01*
X739457Y223545D01*
X738858Y224344D01*
X738459Y225275D01*
X738259Y226340D01*
Y227405D01*
X738459Y228470D01*
X738858Y229401D01*
X739457Y230199D01*
X740156Y230732D01*
X740954Y230865D01*
X741753Y230732D01*
X742452Y230199D01*
X743051Y229401D01*
X743450Y228470D01*
X743650Y227405D01*
Y226340D01*
X743450Y225275D01*
X743051Y224344D01*
X742452Y223545D01*
X741753Y223013D01*
X740954Y222880D01*
G01X748939Y230865D02*
Y222880D01*
G01X747542Y228203D02*
X750337D01*
G01X755228Y222880D02*
Y230865D01*
G01Y227006D02*
X755727Y227671D01*
X756226Y228070D01*
X757024Y228203D01*
X757623Y228070D01*
X758322Y227538D01*
X758621Y226739D01*
Y222880D01*
G01X763412Y226473D02*
X766606D01*
X766307Y227405D01*
X765808Y227937D01*
X765109Y228203D01*
X764410Y228070D01*
X763811Y227671D01*
X763412Y226739D01*
X763213Y225941D01*
Y225142D01*
X763412Y224344D01*
X763911Y223545D01*
X764510Y223013D01*
X765209Y222880D01*
X765908Y223146D01*
X766606Y223944D01*
G01X771497Y222880D02*
Y228203D01*
G01Y227139D02*
X771996Y227671D01*
X772495Y228070D01*
X773194Y228203D01*
X773693Y228070D01*
X774292Y227671D01*
G01X779382Y223811D02*
X779881Y223279D01*
X780580Y222880D01*
X781179D01*
X781778Y223146D01*
X782177Y223545D01*
X782377Y224077D01*
X782277Y224876D01*
X781878Y225275D01*
X780081Y226074D01*
X779682Y227006D01*
X779881Y227671D01*
X780281Y228070D01*
X780879Y228203D01*
X781478Y228070D01*
X782077Y227671D01*
G01X796350Y220218D02*
X795352Y221549D01*
X794853Y222880D01*
Y228203D01*
X795352Y229534D01*
X796350Y230865D01*
G01X804834Y222880D02*
Y230865D01*
G01X812819Y228203D02*
Y222880D01*
G01Y230333D02*
X812620Y230466D01*
Y230732D01*
X812819Y230865D01*
X813019Y230732D01*
Y230466D01*
X812819Y230333D01*
G01X819108Y222880D02*
Y230865D01*
G01X822302Y228203D02*
X819108Y225142D01*
G01X820405Y226340D02*
X822501Y222880D01*
G01X827292Y226473D02*
X830486D01*
X830187Y227405D01*
X829688Y227937D01*
X828989Y228203D01*
X828290Y228070D01*
X827691Y227671D01*
X827292Y226739D01*
X827093Y225941D01*
Y225142D01*
X827292Y224344D01*
X827791Y223545D01*
X828390Y223013D01*
X829089Y222880D01*
X829788Y223146D01*
X830486Y223944D01*
G01X843262Y226473D02*
X846456D01*
X846157Y227405D01*
X845658Y227937D01*
X844959Y228203D01*
X844260Y228070D01*
X843661Y227671D01*
X843262Y226739D01*
X843063Y225941D01*
Y225142D01*
X843262Y224344D01*
X843761Y223545D01*
X844360Y223013D01*
X845059Y222880D01*
X845758Y223146D01*
X846456Y223944D01*
G01X852744Y222880D02*
Y230865D01*
G01X860729Y222880D02*
Y230865D01*
G01X868714Y228203D02*
Y222880D01*
G01Y230333D02*
X868515Y230466D01*
Y230732D01*
X868714Y230865D01*
X868914Y230732D01*
Y230466D01*
X868714Y230333D01*
G01X874903Y220218D02*
Y228203D01*
G01Y227006D02*
X875402Y227671D01*
X875901Y228070D01*
X876699Y228203D01*
X877398Y228070D01*
X878097Y227405D01*
X878396Y226473D01*
X878496Y225542D01*
X878396Y224610D01*
X878097Y223678D01*
X877498Y223146D01*
X876699Y222880D01*
X876001Y223013D01*
X875302Y223412D01*
X874903Y223944D01*
G01X883187Y223811D02*
X883686Y223279D01*
X884385Y222880D01*
X884984D01*
X885583Y223146D01*
X885982Y223545D01*
X886182Y224077D01*
X886082Y224876D01*
X885683Y225275D01*
X883886Y226074D01*
X883487Y227006D01*
X883686Y227671D01*
X884086Y228070D01*
X884684Y228203D01*
X885283Y228070D01*
X885882Y227671D01*
G01X891172Y226473D02*
X894366D01*
X894067Y227405D01*
X893568Y227937D01*
X892869Y228203D01*
X892170Y228070D01*
X891571Y227671D01*
X891172Y226739D01*
X890973Y225941D01*
Y225142D01*
X891172Y224344D01*
X891671Y223545D01*
X892270Y223013D01*
X892969Y222880D01*
X893668Y223146D01*
X894366Y223944D01*
G01X910436Y222880D02*
Y228203D01*
G01Y227272D02*
X910037Y227804D01*
X909438Y228070D01*
X908739Y228203D01*
X908041Y227937D01*
X907442Y227405D01*
X907042Y226606D01*
X906843Y225542D01*
X907042Y224477D01*
X907442Y223678D01*
X908041Y223146D01*
X908739Y222880D01*
X909438Y223013D01*
X910037Y223412D01*
X910436Y223944D01*
G01X914928Y222880D02*
Y228203D01*
G01Y226872D02*
X915327Y227538D01*
X915926Y228070D01*
X916724Y228203D01*
X917423Y228070D01*
X918022Y227538D01*
X918321Y226606D01*
Y222880D01*
G01X926406Y230865D02*
Y222880D01*
G01Y224077D02*
X926007Y223412D01*
X925408Y223013D01*
X924709Y222880D01*
X923911Y223146D01*
X923312Y223811D01*
X922913Y224610D01*
X922813Y225542D01*
X922913Y226473D01*
X923312Y227272D01*
X923911Y227937D01*
X924709Y228203D01*
X925408Y228070D01*
X925907Y227804D01*
X926406Y227272D01*
G01X940579Y222880D02*
X939981Y223013D01*
X939382Y223545D01*
X938982Y224477D01*
X938783Y225542D01*
X938982Y226606D01*
X939382Y227538D01*
X939981Y228070D01*
X940579Y228203D01*
X941178Y228070D01*
X941777Y227538D01*
X942176Y226606D01*
X942276Y225542D01*
X942176Y224477D01*
X941777Y223545D01*
X941178Y223013D01*
X940579Y222880D01*
G01X948564Y230865D02*
Y222880D01*
G01X947167Y228203D02*
X949962D01*
G01X954853Y222880D02*
Y230865D01*
G01Y227006D02*
X955352Y227671D01*
X955851Y228070D01*
X956649Y228203D01*
X957248Y228070D01*
X957947Y227538D01*
X958246Y226739D01*
Y222880D01*
G01X963037Y226473D02*
X966231D01*
X965932Y227405D01*
X965433Y227937D01*
X964734Y228203D01*
X964035Y228070D01*
X963436Y227671D01*
X963037Y226739D01*
X962838Y225941D01*
Y225142D01*
X963037Y224344D01*
X963536Y223545D01*
X964135Y223013D01*
X964834Y222880D01*
X965533Y223146D01*
X966231Y223944D01*
G01X971122Y222880D02*
Y228203D01*
G01Y227139D02*
X971621Y227671D01*
X972120Y228070D01*
X972819Y228203D01*
X973318Y228070D01*
X973917Y227671D01*
G01X979007Y223811D02*
X979506Y223279D01*
X980205Y222880D01*
X980804D01*
X981403Y223146D01*
X981802Y223545D01*
X982002Y224077D01*
X981902Y224876D01*
X981503Y225275D01*
X979706Y226074D01*
X979307Y227006D01*
X979506Y227671D01*
X979906Y228070D01*
X980504Y228203D01*
X981103Y228070D01*
X981702Y227671D01*
G01X988989Y220218D02*
X989987Y221549D01*
X990486Y222880D01*
Y228203D01*
X989987Y229534D01*
X988989Y230865D01*
G01X738958Y234380D02*
Y242365D01*
X741354D01*
X742152Y241966D01*
X742751Y241034D01*
X742951Y239970D01*
X742751Y238905D01*
X742252Y238106D01*
X741354Y237707D01*
X738958D01*
G01X748939Y242365D02*
Y234380D01*
G01X746644Y242365D02*
X751235D01*
G01X754828Y234380D02*
Y242365D01*
G01X759021D02*
Y234380D01*
G01Y238372D02*
X754828D01*
G01X763113Y234114D02*
X766706Y242365D01*
G01X770599Y234380D02*
Y242365D01*
X775190Y234380D01*
Y242365D01*
G01X778883Y234380D02*
Y242365D01*
X781279D01*
X782077Y241966D01*
X782676Y241034D01*
X782876Y239970D01*
X782676Y238905D01*
X782177Y238106D01*
X781279Y237707D01*
X778883D01*
G01X788864Y242365D02*
Y234380D01*
G01X786569Y242365D02*
X791160D01*
G01X794753Y234380D02*
Y242365D01*
G01X798946D02*
Y234380D01*
G01Y238372D02*
X794753D01*
G01X810823Y234380D02*
X814816Y237042D01*
X810823Y239703D01*
G01X819507Y235844D02*
X822102D01*
G01Y238239D02*
X819507D01*
G01X826594Y235577D02*
X827192Y234912D01*
X827891Y234513D01*
X828789Y234380D01*
X829688Y234646D01*
X830386Y235178D01*
X830886Y236110D01*
X830985Y237175D01*
X830786Y238239D01*
X830287Y238905D01*
X829588Y239437D01*
X828889Y239570D01*
X828191Y239437D01*
X827292Y238905D01*
X827592Y242365D01*
X830287D01*
G01X841765Y234380D02*
Y239703D01*
G01Y238239D02*
X842064Y238905D01*
X842564Y239437D01*
X843262Y239703D01*
X843961Y239437D01*
X844460Y238905D01*
X844759Y238239D01*
Y234380D01*
G01Y238239D02*
X845059Y238905D01*
X845558Y239437D01*
X846257Y239703D01*
X846955Y239437D01*
X847455Y238905D01*
X847754Y238106D01*
Y234380D01*
G01X849750D02*
Y239703D01*
G01Y238239D02*
X850049Y238905D01*
X850549Y239437D01*
X851247Y239703D01*
X851946Y239437D01*
X852445Y238905D01*
X852744Y238239D01*
Y234380D01*
G01Y238239D02*
X853044Y238905D01*
X853543Y239437D01*
X854242Y239703D01*
X854940Y239437D01*
X855440Y238905D01*
X855739Y238106D01*
Y234380D01*
G01X739159Y247380D02*
Y255365D01*
X743750Y247380D01*
Y255365D01*
G01X747443Y247380D02*
Y255365D01*
X749839D01*
X750637Y254966D01*
X751236Y254034D01*
X751436Y252970D01*
X751236Y251905D01*
X750737Y251106D01*
X749839Y250707D01*
X747443D01*
G01X757424Y255365D02*
Y247380D01*
G01X755129Y255365D02*
X759720D01*
G01X763313Y247380D02*
Y255365D01*
G01X767506D02*
Y247380D01*
G01Y251372D02*
X763313D01*
G01X779283Y248444D02*
X780082Y247779D01*
X780980Y247380D01*
X781779D01*
X782577Y247779D01*
X783176Y248444D01*
X783476Y249376D01*
X783276Y250308D01*
X782777Y251106D01*
X781879Y251639D01*
X780681Y251905D01*
X779982Y252437D01*
X779683Y253369D01*
X779882Y254300D01*
X780381Y254966D01*
X781080Y255365D01*
X781779D01*
X782478Y255099D01*
X783076Y254433D01*
G01X789364Y252703D02*
Y247380D01*
G01Y254833D02*
X789165Y254966D01*
Y255232D01*
X789364Y255365D01*
X789564Y255232D01*
Y254966D01*
X789364Y254833D01*
G01X795852Y252703D02*
X798847D01*
X795852Y247380D01*
X798847D01*
G01X803837Y250973D02*
X807031D01*
X806732Y251905D01*
X806233Y252437D01*
X805534Y252703D01*
X804835Y252570D01*
X804236Y252171D01*
X803837Y251239D01*
X803638Y250441D01*
Y249642D01*
X803837Y248844D01*
X804336Y248045D01*
X804935Y247513D01*
X805634Y247380D01*
X806333Y247646D01*
X807031Y248444D01*
G01X819408Y254034D02*
X820007Y254833D01*
X820706Y255232D01*
X821504Y255365D01*
X822502Y255099D01*
X823201Y254433D01*
X823401Y253635D01*
X823301Y252836D01*
X822901Y252171D01*
X820905Y250840D01*
X820007Y249909D01*
X819408Y248577D01*
X819208Y247380D01*
X823401D01*
G01X829289Y247114D02*
X829090Y247247D01*
Y247513D01*
X829289Y247646D01*
X829489Y247513D01*
Y247247D01*
X829289Y247114D01*
G01X837274Y247380D02*
Y255365D01*
X836077Y253768D01*
G01Y247380D02*
X838472D01*
G01X845259D02*
X845958Y247513D01*
X846757Y247912D01*
X847256Y248577D01*
X847455Y249509D01*
X847256Y250441D01*
X846657Y251239D01*
X845759Y251639D01*
X844760D01*
X844161Y251905D01*
X843662Y252570D01*
X843463Y253502D01*
X843762Y254433D01*
X844461Y255099D01*
X845259Y255365D01*
X846058Y255099D01*
X846757Y254433D01*
X847056Y253502D01*
X846856Y252570D01*
X846358Y251905D01*
X845759Y251639D01*
X844760D01*
X843862Y251239D01*
X843263Y250441D01*
X843064Y249509D01*
X843263Y248577D01*
X843762Y247912D01*
X844561Y247513D01*
X845259Y247380D01*
G01X850250D02*
Y252703D01*
G01Y251239D02*
X850549Y251905D01*
X851049Y252437D01*
X851747Y252703D01*
X852446Y252437D01*
X852945Y251905D01*
X853244Y251239D01*
Y247380D01*
G01Y251239D02*
X853544Y251905D01*
X854043Y252437D01*
X854742Y252703D01*
X855440Y252437D01*
X855940Y251905D01*
X856239Y251106D01*
Y247380D01*
G01X858235D02*
Y252703D01*
G01Y251239D02*
X858534Y251905D01*
X859034Y252437D01*
X859732Y252703D01*
X860431Y252437D01*
X860930Y251905D01*
X861229Y251239D01*
Y247380D01*
G01Y251239D02*
X861529Y251905D01*
X862028Y252437D01*
X862727Y252703D01*
X863425Y252437D01*
X863925Y251905D01*
X864224Y251106D01*
Y247380D01*
G01X876700Y244718D02*
X875702Y246049D01*
X875203Y247380D01*
Y252703D01*
X875702Y254034D01*
X876700Y255365D01*
G01X885184Y247380D02*
X884586Y247513D01*
X883987Y248045D01*
X883587Y248977D01*
X883388Y250042D01*
X883587Y251106D01*
X883987Y252038D01*
X884586Y252570D01*
X885184Y252703D01*
X885783Y252570D01*
X886382Y252038D01*
X886781Y251106D01*
X886881Y250042D01*
X886781Y248977D01*
X886382Y248045D01*
X885783Y247513D01*
X885184Y247380D01*
G01X891473D02*
Y252703D01*
G01Y251372D02*
X891872Y252038D01*
X892471Y252570D01*
X893269Y252703D01*
X893968Y252570D01*
X894567Y252038D01*
X894866Y251106D01*
Y247380D01*
G01X907343D02*
Y255365D01*
G01Y251372D02*
X907842Y252171D01*
X908441Y252570D01*
X909040Y252703D01*
X909938Y252437D01*
X910537Y251905D01*
X910936Y250973D01*
Y249909D01*
X910736Y248844D01*
X910337Y248045D01*
X909639Y247513D01*
X909040Y247380D01*
X908441Y247513D01*
X907842Y247912D01*
X907343Y248577D01*
G01X915727Y247380D02*
Y252703D01*
G01Y251639D02*
X916226Y252171D01*
X916725Y252570D01*
X917424Y252703D01*
X917923Y252570D01*
X918522Y252171D01*
G01X923612Y250973D02*
X926806D01*
X926507Y251905D01*
X926008Y252437D01*
X925309Y252703D01*
X924610Y252570D01*
X924011Y252171D01*
X923612Y251239D01*
X923413Y250441D01*
Y249642D01*
X923612Y248844D01*
X924111Y248045D01*
X924710Y247513D01*
X925409Y247380D01*
X926108Y247646D01*
X926806Y248444D01*
G01X934891Y247380D02*
Y252703D01*
G01Y251772D02*
X934492Y252304D01*
X933893Y252570D01*
X933194Y252703D01*
X932496Y252437D01*
X931897Y251905D01*
X931497Y251106D01*
X931298Y250042D01*
X931497Y248977D01*
X931897Y248178D01*
X932496Y247646D01*
X933194Y247380D01*
X933893Y247513D01*
X934492Y247912D01*
X934891Y248444D01*
G01X939383Y247380D02*
Y255365D01*
G01X942577Y252703D02*
X939383Y249642D01*
G01X940680Y250840D02*
X942776Y247380D01*
G01X950861D02*
Y252703D01*
G01Y251772D02*
X950462Y252304D01*
X949863Y252570D01*
X949164Y252703D01*
X948466Y252437D01*
X947867Y251905D01*
X947467Y251106D01*
X947268Y250042D01*
X947467Y248977D01*
X947867Y248178D01*
X948466Y247646D01*
X949164Y247380D01*
X949863Y247513D01*
X950462Y247912D01*
X950861Y248444D01*
G01X954554Y252703D02*
X955752Y247380D01*
X957049Y252703D01*
X958347Y247380D01*
X959545Y252703D01*
G01X966831Y247380D02*
Y252703D01*
G01Y251772D02*
X966432Y252304D01*
X965833Y252570D01*
X965134Y252703D01*
X964436Y252437D01*
X963837Y251905D01*
X963437Y251106D01*
X963238Y250042D01*
X963437Y248977D01*
X963837Y248178D01*
X964436Y247646D01*
X965134Y247380D01*
X965833Y247513D01*
X966432Y247912D01*
X966831Y248444D01*
G01X970923Y244985D02*
X971522Y244718D01*
X972321Y244985D01*
X972820Y245517D01*
X973219Y246182D01*
X973818Y248311D01*
X975116Y252703D01*
G01X971921D02*
X973818Y248311D01*
G01X981504Y244718D02*
X982502Y246049D01*
X983001Y247380D01*
Y252703D01*
X982502Y254034D01*
X981504Y255365D01*
G01X739159Y259380D02*
Y267365D01*
X743750Y259380D01*
Y267365D01*
G01X747443Y259380D02*
Y267365D01*
X749839D01*
X750637Y266966D01*
X751236Y266034D01*
X751436Y264970D01*
X751236Y263905D01*
X750737Y263106D01*
X749839Y262707D01*
X747443D01*
G01X757424Y267365D02*
Y259380D01*
G01X755129Y267365D02*
X759720D01*
G01X763313Y259380D02*
Y267365D01*
G01X767506D02*
Y259380D01*
G01Y263372D02*
X763313D01*
G01X779283Y260444D02*
X780082Y259779D01*
X780980Y259380D01*
X781779D01*
X782577Y259779D01*
X783176Y260444D01*
X783476Y261376D01*
X783276Y262308D01*
X782777Y263106D01*
X781879Y263639D01*
X780681Y263905D01*
X779982Y264437D01*
X779683Y265369D01*
X779882Y266300D01*
X780381Y266966D01*
X781080Y267365D01*
X781779D01*
X782478Y267099D01*
X783076Y266433D01*
G01X789364Y264703D02*
Y259380D01*
G01Y266833D02*
X789165Y266966D01*
Y267232D01*
X789364Y267365D01*
X789564Y267232D01*
Y266966D01*
X789364Y266833D01*
G01X795852Y264703D02*
X798847D01*
X795852Y259380D01*
X798847D01*
G01X803837Y262973D02*
X807031D01*
X806732Y263905D01*
X806233Y264437D01*
X805534Y264703D01*
X804835Y264570D01*
X804236Y264171D01*
X803837Y263239D01*
X803638Y262441D01*
Y261642D01*
X803837Y260844D01*
X804336Y260045D01*
X804935Y259513D01*
X805634Y259380D01*
X806333Y259646D01*
X807031Y260444D01*
G01X819109Y260977D02*
X819707Y260045D01*
X820506Y259513D01*
X821404Y259380D01*
X822203Y259513D01*
X823001Y260178D01*
X823500Y260977D01*
X823600Y261775D01*
X823401Y262707D01*
X822702Y263372D01*
X822003Y263639D01*
X821105D01*
G01X822003D02*
X822602Y264038D01*
X823101Y264703D01*
X823301Y265502D01*
X823101Y266300D01*
X822602Y266966D01*
X821704Y267365D01*
X820805Y267232D01*
X819907Y266699D01*
G01X829289Y259114D02*
X829090Y259247D01*
Y259513D01*
X829289Y259646D01*
X829489Y259513D01*
Y259247D01*
X829289Y259114D01*
G01X835079Y260577D02*
X835677Y259912D01*
X836376Y259513D01*
X837274Y259380D01*
X838173Y259646D01*
X838871Y260178D01*
X839371Y261110D01*
X839470Y262175D01*
X839271Y263239D01*
X838772Y263905D01*
X838073Y264437D01*
X837374Y264570D01*
X836676Y264437D01*
X835777Y263905D01*
X836077Y267365D01*
X838772D01*
G01X843064Y260577D02*
X843662Y259912D01*
X844361Y259513D01*
X845259Y259380D01*
X846158Y259646D01*
X846856Y260178D01*
X847356Y261110D01*
X847455Y262175D01*
X847256Y263239D01*
X846757Y263905D01*
X846058Y264437D01*
X845359Y264570D01*
X844661Y264437D01*
X843762Y263905D01*
X844062Y267365D01*
X846757D01*
G01X850250Y259380D02*
Y264703D01*
G01Y263239D02*
X850549Y263905D01*
X851049Y264437D01*
X851747Y264703D01*
X852446Y264437D01*
X852945Y263905D01*
X853244Y263239D01*
Y259380D01*
G01Y263239D02*
X853544Y263905D01*
X854043Y264437D01*
X854742Y264703D01*
X855440Y264437D01*
X855940Y263905D01*
X856239Y263106D01*
Y259380D01*
G01X858235D02*
Y264703D01*
G01Y263239D02*
X858534Y263905D01*
X859034Y264437D01*
X859732Y264703D01*
X860431Y264437D01*
X860930Y263905D01*
X861229Y263239D01*
Y259380D01*
G01Y263239D02*
X861529Y263905D01*
X862028Y264437D01*
X862727Y264703D01*
X863425Y264437D01*
X863925Y263905D01*
X864224Y263106D01*
Y259380D01*
G01X876700Y256718D02*
X875702Y258049D01*
X875203Y259380D01*
Y264703D01*
X875702Y266034D01*
X876700Y267365D01*
G01X885184Y259380D02*
X884586Y259513D01*
X883987Y260045D01*
X883587Y260977D01*
X883388Y262042D01*
X883587Y263106D01*
X883987Y264038D01*
X884586Y264570D01*
X885184Y264703D01*
X885783Y264570D01*
X886382Y264038D01*
X886781Y263106D01*
X886881Y262042D01*
X886781Y260977D01*
X886382Y260045D01*
X885783Y259513D01*
X885184Y259380D01*
G01X891473D02*
Y264703D01*
G01Y263372D02*
X891872Y264038D01*
X892471Y264570D01*
X893269Y264703D01*
X893968Y264570D01*
X894567Y264038D01*
X894866Y263106D01*
Y259380D01*
G01X907343D02*
Y267365D01*
G01Y263372D02*
X907842Y264171D01*
X908441Y264570D01*
X909040Y264703D01*
X909938Y264437D01*
X910537Y263905D01*
X910936Y262973D01*
Y261909D01*
X910736Y260844D01*
X910337Y260045D01*
X909639Y259513D01*
X909040Y259380D01*
X908441Y259513D01*
X907842Y259912D01*
X907343Y260577D01*
G01X915727Y259380D02*
Y264703D01*
G01Y263639D02*
X916226Y264171D01*
X916725Y264570D01*
X917424Y264703D01*
X917923Y264570D01*
X918522Y264171D01*
G01X923612Y262973D02*
X926806D01*
X926507Y263905D01*
X926008Y264437D01*
X925309Y264703D01*
X924610Y264570D01*
X924011Y264171D01*
X923612Y263239D01*
X923413Y262441D01*
Y261642D01*
X923612Y260844D01*
X924111Y260045D01*
X924710Y259513D01*
X925409Y259380D01*
X926108Y259646D01*
X926806Y260444D01*
G01X934891Y259380D02*
Y264703D01*
G01Y263772D02*
X934492Y264304D01*
X933893Y264570D01*
X933194Y264703D01*
X932496Y264437D01*
X931897Y263905D01*
X931497Y263106D01*
X931298Y262042D01*
X931497Y260977D01*
X931897Y260178D01*
X932496Y259646D01*
X933194Y259380D01*
X933893Y259513D01*
X934492Y259912D01*
X934891Y260444D01*
G01X939383Y259380D02*
Y267365D01*
G01X942577Y264703D02*
X939383Y261642D01*
G01X940680Y262840D02*
X942776Y259380D01*
G01X950861D02*
Y264703D01*
G01Y263772D02*
X950462Y264304D01*
X949863Y264570D01*
X949164Y264703D01*
X948466Y264437D01*
X947867Y263905D01*
X947467Y263106D01*
X947268Y262042D01*
X947467Y260977D01*
X947867Y260178D01*
X948466Y259646D01*
X949164Y259380D01*
X949863Y259513D01*
X950462Y259912D01*
X950861Y260444D01*
G01X954554Y264703D02*
X955752Y259380D01*
X957049Y264703D01*
X958347Y259380D01*
X959545Y264703D01*
G01X966831Y259380D02*
Y264703D01*
G01Y263772D02*
X966432Y264304D01*
X965833Y264570D01*
X965134Y264703D01*
X964436Y264437D01*
X963837Y263905D01*
X963437Y263106D01*
X963238Y262042D01*
X963437Y260977D01*
X963837Y260178D01*
X964436Y259646D01*
X965134Y259380D01*
X965833Y259513D01*
X966432Y259912D01*
X966831Y260444D01*
G01X970923Y256985D02*
X971522Y256718D01*
X972321Y256985D01*
X972820Y257517D01*
X973219Y258182D01*
X973818Y260311D01*
X975116Y264703D01*
G01X971921D02*
X973818Y260311D01*
G01X981504Y256718D02*
X982502Y258049D01*
X983001Y259380D01*
Y264703D01*
X982502Y266034D01*
X981504Y267365D01*
G01X739159Y272880D02*
Y280865D01*
X743750Y272880D01*
Y280865D01*
G01X747443Y272880D02*
Y280865D01*
X749839D01*
X750637Y280466D01*
X751236Y279534D01*
X751436Y278470D01*
X751236Y277405D01*
X750737Y276606D01*
X749839Y276207D01*
X747443D01*
G01X757424Y280865D02*
Y272880D01*
G01X755129Y280865D02*
X759720D01*
G01X763313Y272880D02*
Y280865D01*
G01X767506D02*
Y272880D01*
G01Y276872D02*
X763313D01*
G01X779283Y273944D02*
X780082Y273279D01*
X780980Y272880D01*
X781779D01*
X782577Y273279D01*
X783176Y273944D01*
X783476Y274876D01*
X783276Y275808D01*
X782777Y276606D01*
X781879Y277139D01*
X780681Y277405D01*
X779982Y277937D01*
X779683Y278869D01*
X779882Y279800D01*
X780381Y280466D01*
X781080Y280865D01*
X781779D01*
X782478Y280599D01*
X783076Y279933D01*
G01X789364Y278203D02*
Y272880D01*
G01Y280333D02*
X789165Y280466D01*
Y280732D01*
X789364Y280865D01*
X789564Y280732D01*
Y280466D01*
X789364Y280333D01*
G01X795852Y278203D02*
X798847D01*
X795852Y272880D01*
X798847D01*
G01X803837Y276473D02*
X807031D01*
X806732Y277405D01*
X806233Y277937D01*
X805534Y278203D01*
X804835Y278070D01*
X804236Y277671D01*
X803837Y276739D01*
X803638Y275941D01*
Y275142D01*
X803837Y274344D01*
X804336Y273545D01*
X804935Y273013D01*
X805634Y272880D01*
X806333Y273146D01*
X807031Y273944D01*
G01X815316Y272880D02*
X811323Y275542D01*
X815316Y278203D01*
G01X827094Y274077D02*
X827692Y273412D01*
X828391Y273013D01*
X829289Y272880D01*
X830188Y273146D01*
X830886Y273678D01*
X831386Y274610D01*
X831485Y275675D01*
X831286Y276739D01*
X830787Y277405D01*
X830088Y277937D01*
X829389Y278070D01*
X828691Y277937D01*
X827792Y277405D01*
X828092Y280865D01*
X830787D01*
G01X834280Y272880D02*
Y278203D01*
G01Y276739D02*
X834579Y277405D01*
X835079Y277937D01*
X835777Y278203D01*
X836476Y277937D01*
X836975Y277405D01*
X837274Y276739D01*
Y272880D01*
G01Y276739D02*
X837574Y277405D01*
X838073Y277937D01*
X838772Y278203D01*
X839470Y277937D01*
X839970Y277405D01*
X840269Y276606D01*
Y272880D01*
G01X842265D02*
Y278203D01*
G01Y276739D02*
X842564Y277405D01*
X843064Y277937D01*
X843762Y278203D01*
X844461Y277937D01*
X844960Y277405D01*
X845259Y276739D01*
Y272880D01*
G01Y276739D02*
X845559Y277405D01*
X846058Y277937D01*
X846757Y278203D01*
X847455Y277937D01*
X847955Y277405D01*
X848254Y276606D01*
Y272880D01*
G01X860730Y270218D02*
X859732Y271549D01*
X859233Y272880D01*
Y278203D01*
X859732Y279534D01*
X860730Y280865D01*
G01X867518Y272880D02*
Y278203D01*
G01Y276872D02*
X867917Y277538D01*
X868516Y278070D01*
X869314Y278203D01*
X870013Y278070D01*
X870612Y277538D01*
X870911Y276606D01*
Y272880D01*
G01X877199D02*
X876601Y273013D01*
X876002Y273545D01*
X875602Y274477D01*
X875403Y275542D01*
X875602Y276606D01*
X876002Y277538D01*
X876601Y278070D01*
X877199Y278203D01*
X877798Y278070D01*
X878397Y277538D01*
X878796Y276606D01*
X878896Y275542D01*
X878796Y274477D01*
X878397Y273545D01*
X877798Y273013D01*
X877199Y272880D01*
G01X885184Y280865D02*
Y272880D01*
G01X883787Y278203D02*
X886582D01*
G01X901154Y272880D02*
X900556Y273013D01*
X899957Y273545D01*
X899557Y274477D01*
X899358Y275542D01*
X899557Y276606D01*
X899957Y277538D01*
X900556Y278070D01*
X901154Y278203D01*
X901753Y278070D01*
X902352Y277538D01*
X902751Y276606D01*
X902851Y275542D01*
X902751Y274477D01*
X902352Y273545D01*
X901753Y273013D01*
X901154Y272880D01*
G01X907443D02*
Y278203D01*
G01Y276872D02*
X907842Y277538D01*
X908441Y278070D01*
X909239Y278203D01*
X909938Y278070D01*
X910537Y277538D01*
X910836Y276606D01*
Y272880D01*
G01X923313D02*
Y280865D01*
G01Y276872D02*
X923812Y277671D01*
X924411Y278070D01*
X925010Y278203D01*
X925908Y277937D01*
X926507Y277405D01*
X926906Y276473D01*
Y275409D01*
X926706Y274344D01*
X926307Y273545D01*
X925609Y273013D01*
X925010Y272880D01*
X924411Y273013D01*
X923812Y273412D01*
X923313Y274077D01*
G01X931697Y272880D02*
Y278203D01*
G01Y277139D02*
X932196Y277671D01*
X932695Y278070D01*
X933394Y278203D01*
X933893Y278070D01*
X934492Y277671D01*
G01X939582Y276473D02*
X942776D01*
X942477Y277405D01*
X941978Y277937D01*
X941279Y278203D01*
X940580Y278070D01*
X939981Y277671D01*
X939582Y276739D01*
X939383Y275941D01*
Y275142D01*
X939582Y274344D01*
X940081Y273545D01*
X940680Y273013D01*
X941379Y272880D01*
X942078Y273146D01*
X942776Y273944D01*
G01X950861Y272880D02*
Y278203D01*
G01Y277272D02*
X950462Y277804D01*
X949863Y278070D01*
X949164Y278203D01*
X948466Y277937D01*
X947867Y277405D01*
X947467Y276606D01*
X947268Y275542D01*
X947467Y274477D01*
X947867Y273678D01*
X948466Y273146D01*
X949164Y272880D01*
X949863Y273013D01*
X950462Y273412D01*
X950861Y273944D01*
G01X955353Y272880D02*
Y280865D01*
G01X958547Y278203D02*
X955353Y275142D01*
G01X956650Y276340D02*
X958746Y272880D01*
G01X966831D02*
Y278203D01*
G01Y277272D02*
X966432Y277804D01*
X965833Y278070D01*
X965134Y278203D01*
X964436Y277937D01*
X963837Y277405D01*
X963437Y276606D01*
X963238Y275542D01*
X963437Y274477D01*
X963837Y273678D01*
X964436Y273146D01*
X965134Y272880D01*
X965833Y273013D01*
X966432Y273412D01*
X966831Y273944D01*
G01X970524Y278203D02*
X971722Y272880D01*
X973019Y278203D01*
X974317Y272880D01*
X975515Y278203D01*
G01X982801Y272880D02*
Y278203D01*
G01Y277272D02*
X982402Y277804D01*
X981803Y278070D01*
X981104Y278203D01*
X980406Y277937D01*
X979807Y277405D01*
X979407Y276606D01*
X979208Y275542D01*
X979407Y274477D01*
X979807Y273678D01*
X980406Y273146D01*
X981104Y272880D01*
X981803Y273013D01*
X982402Y273412D01*
X982801Y273944D01*
G01X986893Y270485D02*
X987492Y270218D01*
X988291Y270485D01*
X988790Y271017D01*
X989189Y271682D01*
X989788Y273811D01*
X991086Y278203D01*
G01X987891D02*
X989788Y273811D01*
G01X997474Y270218D02*
X998472Y271549D01*
X998971Y272880D01*
Y278203D01*
X998472Y279534D01*
X997474Y280865D01*
G01X738759Y293365D02*
Y287642D01*
X739158Y286444D01*
X739956Y285646D01*
X740954Y285380D01*
X741953Y285646D01*
X742751Y286444D01*
X743150Y287642D01*
Y293365D01*
G01X747243Y285380D02*
Y290703D01*
G01Y289372D02*
X747642Y290038D01*
X748241Y290570D01*
X749039Y290703D01*
X749738Y290570D01*
X750337Y290038D01*
X750636Y289106D01*
Y285380D01*
G01X755627Y288042D02*
X758222D01*
G01X763113Y282718D02*
Y290703D01*
G01Y289506D02*
X763612Y290171D01*
X764111Y290570D01*
X764909Y290703D01*
X765608Y290570D01*
X766307Y289905D01*
X766606Y288973D01*
X766706Y288042D01*
X766606Y287110D01*
X766307Y286178D01*
X765708Y285646D01*
X764909Y285380D01*
X764211Y285513D01*
X763512Y285912D01*
X763113Y286444D01*
G01X772894Y285380D02*
Y293365D01*
G01X779183Y290703D02*
Y286977D01*
X779582Y286045D01*
X780181Y285513D01*
X780879Y285380D01*
X781578Y285513D01*
X782177Y286045D01*
X782576Y286977D01*
G01Y285380D02*
Y290703D01*
G01X787467Y283384D02*
X788166Y282851D01*
X788964Y282718D01*
X789663Y282851D01*
X790262Y283517D01*
X790661Y284448D01*
Y290703D01*
G01Y289639D02*
X790262Y290171D01*
X789663Y290570D01*
X788964Y290703D01*
X788166Y290437D01*
X787667Y289905D01*
X787267Y288973D01*
X787068Y288042D01*
X787168Y287243D01*
X787567Y286311D01*
X788166Y285646D01*
X788964Y285380D01*
X789563Y285513D01*
X790262Y286045D01*
X790661Y286577D01*
G01X795452Y283384D02*
X796151Y282851D01*
X796949Y282718D01*
X797648Y282851D01*
X798247Y283517D01*
X798646Y284448D01*
Y290703D01*
G01Y289639D02*
X798247Y290171D01*
X797648Y290570D01*
X796949Y290703D01*
X796151Y290437D01*
X795652Y289905D01*
X795252Y288973D01*
X795053Y288042D01*
X795153Y287243D01*
X795552Y286311D01*
X796151Y285646D01*
X796949Y285380D01*
X797548Y285513D01*
X798247Y286045D01*
X798646Y286577D01*
G01X803337Y288973D02*
X806531D01*
X806232Y289905D01*
X805733Y290437D01*
X805034Y290703D01*
X804335Y290570D01*
X803736Y290171D01*
X803337Y289239D01*
X803138Y288441D01*
Y287642D01*
X803337Y286844D01*
X803836Y286045D01*
X804435Y285513D01*
X805134Y285380D01*
X805833Y285646D01*
X806531Y286444D01*
G01X814616Y293365D02*
Y285380D01*
G01Y286577D02*
X814217Y285912D01*
X813618Y285513D01*
X812919Y285380D01*
X812121Y285646D01*
X811522Y286311D01*
X811123Y287110D01*
X811023Y288042D01*
X811123Y288973D01*
X811522Y289772D01*
X812121Y290437D01*
X812919Y290703D01*
X813618Y290570D01*
X814117Y290304D01*
X814616Y289772D01*
G01X826793Y285380D02*
Y293365D01*
X829189D01*
X829987Y292966D01*
X830586Y292034D01*
X830786Y290970D01*
X830586Y289905D01*
X830087Y289106D01*
X829189Y288707D01*
X826793D01*
G01X836774Y293365D02*
Y285380D01*
G01X834479Y293365D02*
X839070D01*
G01X842663Y285380D02*
Y293365D01*
G01X846856D02*
Y285380D01*
G01Y289372D02*
X842663D01*
G01X860230Y282718D02*
X859232Y284049D01*
X858733Y285380D01*
Y290703D01*
X859232Y292034D01*
X860230Y293365D01*
G01X866618Y285380D02*
Y293365D01*
G01X870811D02*
Y285380D01*
G01Y289372D02*
X866618D01*
G01X876699Y285380D02*
X876101Y285513D01*
X875502Y286045D01*
X875102Y286977D01*
X874903Y288042D01*
X875102Y289106D01*
X875502Y290038D01*
X876101Y290570D01*
X876699Y290703D01*
X877298Y290570D01*
X877897Y290038D01*
X878296Y289106D01*
X878396Y288042D01*
X878296Y286977D01*
X877897Y286045D01*
X877298Y285513D01*
X876699Y285380D01*
G01X884684D02*
Y293365D01*
G01X891172Y288973D02*
X894366D01*
X894067Y289905D01*
X893568Y290437D01*
X892869Y290703D01*
X892170Y290570D01*
X891571Y290171D01*
X891172Y289239D01*
X890973Y288441D01*
Y287642D01*
X891172Y286844D01*
X891671Y286045D01*
X892270Y285513D01*
X892969Y285380D01*
X893668Y285646D01*
X894366Y286444D01*
G01X906543D02*
X907342Y285779D01*
X908240Y285380D01*
X909039D01*
X909837Y285779D01*
X910436Y286444D01*
X910736Y287376D01*
X910536Y288308D01*
X910037Y289106D01*
X909139Y289639D01*
X907941Y289905D01*
X907242Y290437D01*
X906943Y291369D01*
X907142Y292300D01*
X907641Y292966D01*
X908340Y293365D01*
X909039D01*
X909738Y293099D01*
X910336Y292433D01*
G01X916624Y290703D02*
Y285380D01*
G01Y292833D02*
X916425Y292966D01*
Y293232D01*
X916624Y293365D01*
X916824Y293232D01*
Y292966D01*
X916624Y292833D01*
G01X923112Y290703D02*
X926107D01*
X923112Y285380D01*
X926107D01*
G01X931097Y288973D02*
X934291D01*
X933992Y289905D01*
X933493Y290437D01*
X932794Y290703D01*
X932095Y290570D01*
X931496Y290171D01*
X931097Y289239D01*
X930898Y288441D01*
Y287642D01*
X931097Y286844D01*
X931596Y286045D01*
X932195Y285513D01*
X932894Y285380D01*
X933593Y285646D01*
X934291Y286444D01*
G01X942576Y285380D02*
X938583Y288042D01*
X942576Y290703D01*
G01X948564Y285380D02*
Y293365D01*
X947367Y291768D01*
G01Y285380D02*
X949762D01*
G01X954853Y286311D02*
X955551Y285646D01*
X956350Y285380D01*
X957148Y285646D01*
X957847Y286444D01*
X958346Y287642D01*
X958546Y288840D01*
Y290304D01*
X958346Y291502D01*
X957847Y292566D01*
X957248Y293099D01*
X956549Y293365D01*
X955751Y293099D01*
X955152Y292566D01*
X954753Y291768D01*
X954553Y290703D01*
X954753Y289772D01*
X955252Y288840D01*
X955851Y288308D01*
X956549Y288175D01*
X957348Y288441D01*
X957947Y289106D01*
X958546Y290304D01*
G01X964335Y285380D02*
X964534Y287110D01*
X964834Y288574D01*
X965233Y289905D01*
X965732Y291369D01*
X966531Y293365D01*
X962538D01*
G01X969525Y285380D02*
Y290703D01*
G01Y289239D02*
X969824Y289905D01*
X970324Y290437D01*
X971022Y290703D01*
X971721Y290437D01*
X972220Y289905D01*
X972519Y289239D01*
Y285380D01*
G01Y289239D02*
X972819Y289905D01*
X973318Y290437D01*
X974017Y290703D01*
X974715Y290437D01*
X975215Y289905D01*
X975514Y289106D01*
Y285380D01*
G01X980504Y290703D02*
Y285380D01*
G01Y292833D02*
X980305Y292966D01*
Y293232D01*
X980504Y293365D01*
X980704Y293232D01*
Y292966D01*
X980504Y292833D01*
G01X988489Y285380D02*
Y293365D01*
G01X1001964Y290703D02*
X1003162Y285380D01*
X1004459Y290703D01*
X1005757Y285380D01*
X1006955Y290703D01*
G01X1012444D02*
Y285380D01*
G01Y292833D02*
X1012245Y292966D01*
Y293232D01*
X1012444Y293365D01*
X1012644Y293232D01*
Y292966D01*
X1012444Y292833D01*
G01X1020429Y293365D02*
Y285380D01*
G01X1019032Y290703D02*
X1021827D01*
G01X1026718Y285380D02*
Y293365D01*
G01Y289506D02*
X1027217Y290171D01*
X1027716Y290570D01*
X1028514Y290703D01*
X1029113Y290570D01*
X1029812Y290038D01*
X1030111Y289239D01*
Y285380D01*
G01X1042288D02*
Y293365D01*
G01X1046481D02*
Y285380D01*
G01Y289372D02*
X1042288D01*
G01X1049874Y285380D02*
X1052369Y293365D01*
X1054865Y285380D01*
G01X1053966Y288175D02*
X1050772D01*
G01X1058258Y286444D02*
X1059057Y285779D01*
X1059955Y285380D01*
X1060754D01*
X1061552Y285779D01*
X1062151Y286444D01*
X1062451Y287376D01*
X1062251Y288308D01*
X1061752Y289106D01*
X1060854Y289639D01*
X1059656Y289905D01*
X1058957Y290437D01*
X1058658Y291369D01*
X1058857Y292300D01*
X1059356Y292966D01*
X1060055Y293365D01*
X1060754D01*
X1061453Y293099D01*
X1062051Y292433D01*
G01X1066343Y293365D02*
Y285380D01*
X1070336D01*
G01X1082513Y282718D02*
Y290703D01*
G01Y289506D02*
X1083012Y290171D01*
X1083511Y290570D01*
X1084309Y290703D01*
X1085008Y290570D01*
X1085707Y289905D01*
X1086006Y288973D01*
X1086106Y288042D01*
X1086006Y287110D01*
X1085707Y286178D01*
X1085108Y285646D01*
X1084309Y285380D01*
X1083611Y285513D01*
X1082912Y285912D01*
X1082513Y286444D01*
G01X1090897Y285380D02*
Y290703D01*
G01Y289639D02*
X1091396Y290171D01*
X1091895Y290570D01*
X1092594Y290703D01*
X1093093Y290570D01*
X1093692Y290171D01*
G01X1100279Y285380D02*
X1099681Y285513D01*
X1099082Y286045D01*
X1098682Y286977D01*
X1098483Y288042D01*
X1098682Y289106D01*
X1099082Y290038D01*
X1099681Y290570D01*
X1100279Y290703D01*
X1100878Y290570D01*
X1101477Y290038D01*
X1101876Y289106D01*
X1101976Y288042D01*
X1101876Y286977D01*
X1101477Y286045D01*
X1100878Y285513D01*
X1100279Y285380D01*
G01X1110061Y293365D02*
Y285380D01*
G01Y286577D02*
X1109662Y285912D01*
X1109063Y285513D01*
X1108364Y285380D01*
X1107566Y285646D01*
X1106967Y286311D01*
X1106568Y287110D01*
X1106468Y288042D01*
X1106568Y288973D01*
X1106967Y289772D01*
X1107566Y290437D01*
X1108364Y290703D01*
X1109063Y290570D01*
X1109562Y290304D01*
X1110061Y289772D01*
G01X1114553Y290703D02*
Y286977D01*
X1114952Y286045D01*
X1115551Y285513D01*
X1116249Y285380D01*
X1116948Y285513D01*
X1117547Y286045D01*
X1117946Y286977D01*
G01Y285380D02*
Y290703D01*
G01X1125831Y290038D02*
X1125133Y290570D01*
X1124534Y290703D01*
X1123735Y290437D01*
X1123136Y289905D01*
X1122737Y288973D01*
X1122637Y288042D01*
X1122737Y287110D01*
X1123136Y286311D01*
X1123735Y285646D01*
X1124534Y285380D01*
X1125233Y285646D01*
X1125831Y286178D01*
G01X1132219Y293365D02*
Y285380D01*
G01X1130822Y290703D02*
X1133617D01*
G01X1138707Y286311D02*
X1139206Y285779D01*
X1139905Y285380D01*
X1140504D01*
X1141103Y285646D01*
X1141502Y286045D01*
X1141702Y286577D01*
X1141602Y287376D01*
X1141203Y287775D01*
X1139406Y288574D01*
X1139007Y289506D01*
X1139206Y290171D01*
X1139606Y290570D01*
X1140204Y290703D01*
X1140803Y290570D01*
X1141402Y290171D01*
G01X1148689Y282718D02*
X1149687Y284049D01*
X1150186Y285380D01*
Y290703D01*
X1149687Y292034D01*
X1148689Y293365D01*
G01X738759Y305865D02*
Y300142D01*
X739158Y298944D01*
X739956Y298146D01*
X740954Y297880D01*
X741953Y298146D01*
X742751Y298944D01*
X743150Y300142D01*
Y305865D01*
G01X747243Y297880D02*
Y303203D01*
G01Y301872D02*
X747642Y302538D01*
X748241Y303070D01*
X749039Y303203D01*
X749738Y303070D01*
X750337Y302538D01*
X750636Y301606D01*
Y297880D01*
G01X755627Y300542D02*
X758222D01*
G01X763113Y295218D02*
Y303203D01*
G01Y302006D02*
X763612Y302671D01*
X764111Y303070D01*
X764909Y303203D01*
X765608Y303070D01*
X766307Y302405D01*
X766606Y301473D01*
X766706Y300542D01*
X766606Y299610D01*
X766307Y298678D01*
X765708Y298146D01*
X764909Y297880D01*
X764211Y298013D01*
X763512Y298412D01*
X763113Y298944D01*
G01X772894Y297880D02*
Y305865D01*
G01X779183Y303203D02*
Y299477D01*
X779582Y298545D01*
X780181Y298013D01*
X780879Y297880D01*
X781578Y298013D01*
X782177Y298545D01*
X782576Y299477D01*
G01Y297880D02*
Y303203D01*
G01X787467Y295884D02*
X788166Y295351D01*
X788964Y295218D01*
X789663Y295351D01*
X790262Y296017D01*
X790661Y296948D01*
Y303203D01*
G01Y302139D02*
X790262Y302671D01*
X789663Y303070D01*
X788964Y303203D01*
X788166Y302937D01*
X787667Y302405D01*
X787267Y301473D01*
X787068Y300542D01*
X787168Y299743D01*
X787567Y298811D01*
X788166Y298146D01*
X788964Y297880D01*
X789563Y298013D01*
X790262Y298545D01*
X790661Y299077D01*
G01X795452Y295884D02*
X796151Y295351D01*
X796949Y295218D01*
X797648Y295351D01*
X798247Y296017D01*
X798646Y296948D01*
Y303203D01*
G01Y302139D02*
X798247Y302671D01*
X797648Y303070D01*
X796949Y303203D01*
X796151Y302937D01*
X795652Y302405D01*
X795252Y301473D01*
X795053Y300542D01*
X795153Y299743D01*
X795552Y298811D01*
X796151Y298146D01*
X796949Y297880D01*
X797548Y298013D01*
X798247Y298545D01*
X798646Y299077D01*
G01X803337Y301473D02*
X806531D01*
X806232Y302405D01*
X805733Y302937D01*
X805034Y303203D01*
X804335Y303070D01*
X803736Y302671D01*
X803337Y301739D01*
X803138Y300941D01*
Y300142D01*
X803337Y299344D01*
X803836Y298545D01*
X804435Y298013D01*
X805134Y297880D01*
X805833Y298146D01*
X806531Y298944D01*
G01X814616Y305865D02*
Y297880D01*
G01Y299077D02*
X814217Y298412D01*
X813618Y298013D01*
X812919Y297880D01*
X812121Y298146D01*
X811522Y298811D01*
X811123Y299610D01*
X811023Y300542D01*
X811123Y301473D01*
X811522Y302272D01*
X812121Y302937D01*
X812919Y303203D01*
X813618Y303070D01*
X814117Y302804D01*
X814616Y302272D01*
G01X826793Y297880D02*
Y305865D01*
X829189D01*
X829987Y305466D01*
X830586Y304534D01*
X830786Y303470D01*
X830586Y302405D01*
X830087Y301606D01*
X829189Y301207D01*
X826793D01*
G01X836774Y305865D02*
Y297880D01*
G01X834479Y305865D02*
X839070D01*
G01X842663Y297880D02*
Y305865D01*
G01X846856D02*
Y297880D01*
G01Y301872D02*
X842663D01*
G01X860230Y295218D02*
X859232Y296549D01*
X858733Y297880D01*
Y303203D01*
X859232Y304534D01*
X860230Y305865D01*
G01X866618Y297880D02*
Y305865D01*
G01X870811D02*
Y297880D01*
G01Y301872D02*
X866618D01*
G01X876699Y297880D02*
X876101Y298013D01*
X875502Y298545D01*
X875102Y299477D01*
X874903Y300542D01*
X875102Y301606D01*
X875502Y302538D01*
X876101Y303070D01*
X876699Y303203D01*
X877298Y303070D01*
X877897Y302538D01*
X878296Y301606D01*
X878396Y300542D01*
X878296Y299477D01*
X877897Y298545D01*
X877298Y298013D01*
X876699Y297880D01*
G01X884684D02*
Y305865D01*
G01X891172Y301473D02*
X894366D01*
X894067Y302405D01*
X893568Y302937D01*
X892869Y303203D01*
X892170Y303070D01*
X891571Y302671D01*
X891172Y301739D01*
X890973Y300941D01*
Y300142D01*
X891172Y299344D01*
X891671Y298545D01*
X892270Y298013D01*
X892969Y297880D01*
X893668Y298146D01*
X894366Y298944D01*
G01X906543D02*
X907342Y298279D01*
X908240Y297880D01*
X909039D01*
X909837Y298279D01*
X910436Y298944D01*
X910736Y299876D01*
X910536Y300808D01*
X910037Y301606D01*
X909139Y302139D01*
X907941Y302405D01*
X907242Y302937D01*
X906943Y303869D01*
X907142Y304800D01*
X907641Y305466D01*
X908340Y305865D01*
X909039D01*
X909738Y305599D01*
X910336Y304933D01*
G01X916624Y303203D02*
Y297880D01*
G01Y305333D02*
X916425Y305466D01*
Y305732D01*
X916624Y305865D01*
X916824Y305732D01*
Y305466D01*
X916624Y305333D01*
G01X923112Y303203D02*
X926107D01*
X923112Y297880D01*
X926107D01*
G01X931097Y301473D02*
X934291D01*
X933992Y302405D01*
X933493Y302937D01*
X932794Y303203D01*
X932095Y303070D01*
X931496Y302671D01*
X931097Y301739D01*
X930898Y300941D01*
Y300142D01*
X931097Y299344D01*
X931596Y298545D01*
X932195Y298013D01*
X932894Y297880D01*
X933593Y298146D01*
X934291Y298944D01*
G01X942576Y297880D02*
X938583Y300542D01*
X942576Y303203D01*
G01X948564Y297880D02*
Y305865D01*
X947367Y304268D01*
G01Y297880D02*
X949762D01*
G01X954853Y298811D02*
X955551Y298146D01*
X956350Y297880D01*
X957148Y298146D01*
X957847Y298944D01*
X958346Y300142D01*
X958546Y301340D01*
Y302804D01*
X958346Y304002D01*
X957847Y305066D01*
X957248Y305599D01*
X956549Y305865D01*
X955751Y305599D01*
X955152Y305066D01*
X954753Y304268D01*
X954553Y303203D01*
X954753Y302272D01*
X955252Y301340D01*
X955851Y300808D01*
X956549Y300675D01*
X957348Y300941D01*
X957947Y301606D01*
X958546Y302804D01*
G01X964335Y297880D02*
X964534Y299610D01*
X964834Y301074D01*
X965233Y302405D01*
X965732Y303869D01*
X966531Y305865D01*
X962538D01*
G01X969525Y297880D02*
Y303203D01*
G01Y301739D02*
X969824Y302405D01*
X970324Y302937D01*
X971022Y303203D01*
X971721Y302937D01*
X972220Y302405D01*
X972519Y301739D01*
Y297880D01*
G01Y301739D02*
X972819Y302405D01*
X973318Y302937D01*
X974017Y303203D01*
X974715Y302937D01*
X975215Y302405D01*
X975514Y301606D01*
Y297880D01*
G01X980504Y303203D02*
Y297880D01*
G01Y305333D02*
X980305Y305466D01*
Y305732D01*
X980504Y305865D01*
X980704Y305732D01*
Y305466D01*
X980504Y305333D01*
G01X988489Y297880D02*
Y305865D01*
G01X1001964Y303203D02*
X1003162Y297880D01*
X1004459Y303203D01*
X1005757Y297880D01*
X1006955Y303203D01*
G01X1012444D02*
Y297880D01*
G01Y305333D02*
X1012245Y305466D01*
Y305732D01*
X1012444Y305865D01*
X1012644Y305732D01*
Y305466D01*
X1012444Y305333D01*
G01X1020429Y305865D02*
Y297880D01*
G01X1019032Y303203D02*
X1021827D01*
G01X1026718Y297880D02*
Y305865D01*
G01Y302006D02*
X1027217Y302671D01*
X1027716Y303070D01*
X1028514Y303203D01*
X1029113Y303070D01*
X1029812Y302538D01*
X1030111Y301739D01*
Y297880D01*
G01X1042688D02*
Y303203D01*
G01Y301872D02*
X1043087Y302538D01*
X1043686Y303070D01*
X1044484Y303203D01*
X1045183Y303070D01*
X1045782Y302538D01*
X1046081Y301606D01*
Y297880D01*
G01X1052369D02*
X1051771Y298013D01*
X1051172Y298545D01*
X1050772Y299477D01*
X1050573Y300542D01*
X1050772Y301606D01*
X1051172Y302538D01*
X1051771Y303070D01*
X1052369Y303203D01*
X1052968Y303070D01*
X1053567Y302538D01*
X1053966Y301606D01*
X1054066Y300542D01*
X1053966Y299477D01*
X1053567Y298545D01*
X1052968Y298013D01*
X1052369Y297880D01*
G01X1058658D02*
Y303203D01*
G01Y301872D02*
X1059057Y302538D01*
X1059656Y303070D01*
X1060454Y303203D01*
X1061153Y303070D01*
X1061752Y302538D01*
X1062051Y301606D01*
Y297880D01*
G01X1067042Y300542D02*
X1069637D01*
G01X1074228Y297880D02*
Y305865D01*
G01X1078421D02*
Y297880D01*
G01Y301872D02*
X1074228D01*
G01X1081814Y297880D02*
X1084309Y305865D01*
X1086805Y297880D01*
G01X1085906Y300675D02*
X1082712D01*
G01X1090198Y298944D02*
X1090997Y298279D01*
X1091895Y297880D01*
X1092694D01*
X1093492Y298279D01*
X1094091Y298944D01*
X1094391Y299876D01*
X1094191Y300808D01*
X1093692Y301606D01*
X1092794Y302139D01*
X1091596Y302405D01*
X1090897Y302937D01*
X1090598Y303869D01*
X1090797Y304800D01*
X1091296Y305466D01*
X1091995Y305865D01*
X1092694D01*
X1093393Y305599D01*
X1093991Y304933D01*
G01X1098283Y305865D02*
Y297880D01*
X1102276D01*
G01X1114453Y295218D02*
Y303203D01*
G01Y302006D02*
X1114952Y302671D01*
X1115451Y303070D01*
X1116249Y303203D01*
X1116948Y303070D01*
X1117647Y302405D01*
X1117946Y301473D01*
X1118046Y300542D01*
X1117946Y299610D01*
X1117647Y298678D01*
X1117048Y298146D01*
X1116249Y297880D01*
X1115551Y298013D01*
X1114852Y298412D01*
X1114453Y298944D01*
G01X1122837Y297880D02*
Y303203D01*
G01Y302139D02*
X1123336Y302671D01*
X1123835Y303070D01*
X1124534Y303203D01*
X1125033Y303070D01*
X1125632Y302671D01*
G01X1132219Y297880D02*
X1131621Y298013D01*
X1131022Y298545D01*
X1130622Y299477D01*
X1130423Y300542D01*
X1130622Y301606D01*
X1131022Y302538D01*
X1131621Y303070D01*
X1132219Y303203D01*
X1132818Y303070D01*
X1133417Y302538D01*
X1133816Y301606D01*
X1133916Y300542D01*
X1133816Y299477D01*
X1133417Y298545D01*
X1132818Y298013D01*
X1132219Y297880D01*
G01X1142001Y305865D02*
Y297880D01*
G01Y299077D02*
X1141602Y298412D01*
X1141003Y298013D01*
X1140304Y297880D01*
X1139506Y298146D01*
X1138907Y298811D01*
X1138508Y299610D01*
X1138408Y300542D01*
X1138508Y301473D01*
X1138907Y302272D01*
X1139506Y302937D01*
X1140304Y303203D01*
X1141003Y303070D01*
X1141502Y302804D01*
X1142001Y302272D01*
G01X1146493Y303203D02*
Y299477D01*
X1146892Y298545D01*
X1147491Y298013D01*
X1148189Y297880D01*
X1148888Y298013D01*
X1149487Y298545D01*
X1149886Y299477D01*
G01Y297880D02*
Y303203D01*
G01X1157771Y302538D02*
X1157073Y303070D01*
X1156474Y303203D01*
X1155675Y302937D01*
X1155076Y302405D01*
X1154677Y301473D01*
X1154577Y300542D01*
X1154677Y299610D01*
X1155076Y298811D01*
X1155675Y298146D01*
X1156474Y297880D01*
X1157173Y298146D01*
X1157771Y298678D01*
G01X1164159Y305865D02*
Y297880D01*
G01X1162762Y303203D02*
X1165557D01*
G01X1170647Y298811D02*
X1171146Y298279D01*
X1171845Y297880D01*
X1172444D01*
X1173043Y298146D01*
X1173442Y298545D01*
X1173642Y299077D01*
X1173542Y299876D01*
X1173143Y300275D01*
X1171346Y301074D01*
X1170947Y302006D01*
X1171146Y302671D01*
X1171546Y303070D01*
X1172144Y303203D01*
X1172743Y303070D01*
X1173342Y302671D01*
G01X1180629Y295218D02*
X1181627Y296549D01*
X1182126Y297880D01*
Y303203D01*
X1181627Y304534D01*
X1180629Y305865D01*
G01X738458Y318365D02*
Y310380D01*
X742451D01*
G01X750236D02*
Y315703D01*
G01Y314772D02*
X749837Y315304D01*
X749238Y315570D01*
X748539Y315703D01*
X747841Y315437D01*
X747242Y314905D01*
X746842Y314106D01*
X746643Y313042D01*
X746842Y311977D01*
X747242Y311178D01*
X747841Y310646D01*
X748539Y310380D01*
X749238Y310513D01*
X749837Y310912D01*
X750236Y311444D01*
G01X754927Y311311D02*
X755426Y310779D01*
X756125Y310380D01*
X756724D01*
X757323Y310646D01*
X757722Y311045D01*
X757922Y311577D01*
X757822Y312376D01*
X757423Y312775D01*
X755626Y313574D01*
X755227Y314506D01*
X755426Y315171D01*
X755826Y315570D01*
X756424Y315703D01*
X757023Y315570D01*
X757622Y315171D01*
G01X762912Y313973D02*
X766106D01*
X765807Y314905D01*
X765308Y315437D01*
X764609Y315703D01*
X763910Y315570D01*
X763311Y315171D01*
X762912Y314239D01*
X762713Y313441D01*
Y312642D01*
X762912Y311844D01*
X763411Y311045D01*
X764010Y310513D01*
X764709Y310380D01*
X765408Y310646D01*
X766106Y311444D01*
G01X770997Y310380D02*
Y315703D01*
G01Y314639D02*
X771496Y315171D01*
X771995Y315570D01*
X772694Y315703D01*
X773193Y315570D01*
X773792Y315171D01*
G01X786568Y315703D02*
X788364Y310380D01*
X790161Y315703D01*
G01X796349D02*
Y310380D01*
G01Y317833D02*
X796150Y317966D01*
Y318232D01*
X796349Y318365D01*
X796549Y318232D01*
Y317966D01*
X796349Y317833D01*
G01X806131Y310380D02*
Y315703D01*
G01Y314772D02*
X805732Y315304D01*
X805133Y315570D01*
X804434Y315703D01*
X803736Y315437D01*
X803137Y314905D01*
X802737Y314106D01*
X802538Y313042D01*
X802737Y311977D01*
X803137Y311178D01*
X803736Y310646D01*
X804434Y310380D01*
X805133Y310513D01*
X805732Y310912D01*
X806131Y311444D01*
G01X818608Y310380D02*
Y318365D01*
G01Y314506D02*
X819107Y315171D01*
X819606Y315570D01*
X820404Y315703D01*
X821003Y315570D01*
X821702Y315038D01*
X822001Y314239D01*
Y310380D01*
G01X828289D02*
X827691Y310513D01*
X827092Y311045D01*
X826692Y311977D01*
X826493Y313042D01*
X826692Y314106D01*
X827092Y315038D01*
X827691Y315570D01*
X828289Y315703D01*
X828888Y315570D01*
X829487Y315038D01*
X829886Y314106D01*
X829986Y313042D01*
X829886Y311977D01*
X829487Y311045D01*
X828888Y310513D01*
X828289Y310380D01*
G01X836274D02*
Y318365D01*
G01X842762Y313973D02*
X845956D01*
X845657Y314905D01*
X845158Y315437D01*
X844459Y315703D01*
X843760Y315570D01*
X843161Y315171D01*
X842762Y314239D01*
X842563Y313441D01*
Y312642D01*
X842762Y311844D01*
X843261Y311045D01*
X843860Y310513D01*
X844559Y310380D01*
X845258Y310646D01*
X845956Y311444D01*
G01X859730Y307718D02*
X858732Y309049D01*
X858233Y310380D01*
Y315703D01*
X858732Y317034D01*
X859730Y318365D01*
G01X866418Y310380D02*
Y318365D01*
G01Y314372D02*
X866917Y315171D01*
X867516Y315570D01*
X868115Y315703D01*
X869013Y315437D01*
X869612Y314905D01*
X870011Y313973D01*
Y312909D01*
X869811Y311844D01*
X869412Y311045D01*
X868714Y310513D01*
X868115Y310380D01*
X867516Y310513D01*
X866917Y310912D01*
X866418Y311577D01*
G01X874702Y313973D02*
X877896D01*
X877597Y314905D01*
X877098Y315437D01*
X876399Y315703D01*
X875700Y315570D01*
X875101Y315171D01*
X874702Y314239D01*
X874503Y313441D01*
Y312642D01*
X874702Y311844D01*
X875201Y311045D01*
X875800Y310513D01*
X876499Y310380D01*
X877198Y310646D01*
X877896Y311444D01*
G01X883586Y310380D02*
Y317167D01*
X883785Y317833D01*
X884184Y318232D01*
X884783Y318365D01*
X885382Y318099D01*
X885682Y317433D01*
G01X884484Y315171D02*
X882488D01*
G01X892169Y310380D02*
X891571Y310513D01*
X890972Y311045D01*
X890572Y311977D01*
X890373Y313042D01*
X890572Y314106D01*
X890972Y315038D01*
X891571Y315570D01*
X892169Y315703D01*
X892768Y315570D01*
X893367Y315038D01*
X893766Y314106D01*
X893866Y313042D01*
X893766Y311977D01*
X893367Y311045D01*
X892768Y310513D01*
X892169Y310380D01*
G01X898757D02*
Y315703D01*
G01Y314639D02*
X899256Y315171D01*
X899755Y315570D01*
X900454Y315703D01*
X900953Y315570D01*
X901552Y315171D01*
G01X906642Y313973D02*
X909836D01*
X909537Y314905D01*
X909038Y315437D01*
X908339Y315703D01*
X907640Y315570D01*
X907041Y315171D01*
X906642Y314239D01*
X906443Y313441D01*
Y312642D01*
X906642Y311844D01*
X907141Y311045D01*
X907740Y310513D01*
X908439Y310380D01*
X909138Y310646D01*
X909836Y311444D01*
G01X924109Y318365D02*
Y310380D01*
G01X922712Y315703D02*
X925507D01*
G01X930398Y310380D02*
Y318365D01*
G01Y314506D02*
X930897Y315171D01*
X931396Y315570D01*
X932194Y315703D01*
X932793Y315570D01*
X933492Y315038D01*
X933791Y314239D01*
Y310380D01*
G01X938582Y313973D02*
X941776D01*
X941477Y314905D01*
X940978Y315437D01*
X940279Y315703D01*
X939580Y315570D01*
X938981Y315171D01*
X938582Y314239D01*
X938383Y313441D01*
Y312642D01*
X938582Y311844D01*
X939081Y311045D01*
X939680Y310513D01*
X940379Y310380D01*
X941078Y310646D01*
X941776Y311444D01*
G01X957646Y315038D02*
X956948Y315570D01*
X956349Y315703D01*
X955550Y315437D01*
X954951Y314905D01*
X954552Y313973D01*
X954452Y313042D01*
X954552Y312110D01*
X954951Y311311D01*
X955550Y310646D01*
X956349Y310380D01*
X957048Y310646D01*
X957646Y311178D01*
G01X964034Y310380D02*
X963436Y310513D01*
X962837Y311045D01*
X962437Y311977D01*
X962238Y313042D01*
X962437Y314106D01*
X962837Y315038D01*
X963436Y315570D01*
X964034Y315703D01*
X964633Y315570D01*
X965232Y315038D01*
X965631Y314106D01*
X965731Y313042D01*
X965631Y311977D01*
X965232Y311045D01*
X964633Y310513D01*
X964034Y310380D01*
G01X970223Y307718D02*
Y315703D01*
G01Y314506D02*
X970722Y315171D01*
X971221Y315570D01*
X972019Y315703D01*
X972718Y315570D01*
X973417Y314905D01*
X973716Y313973D01*
X973816Y313042D01*
X973716Y312110D01*
X973417Y311178D01*
X972818Y310646D01*
X972019Y310380D01*
X971321Y310513D01*
X970622Y310912D01*
X970223Y311444D01*
G01X978208Y307718D02*
Y315703D01*
G01Y314506D02*
X978707Y315171D01*
X979206Y315570D01*
X980004Y315703D01*
X980703Y315570D01*
X981402Y314905D01*
X981701Y313973D01*
X981801Y313042D01*
X981701Y312110D01*
X981402Y311178D01*
X980803Y310646D01*
X980004Y310380D01*
X979306Y310513D01*
X978607Y310912D01*
X978208Y311444D01*
G01X986492Y313973D02*
X989686D01*
X989387Y314905D01*
X988888Y315437D01*
X988189Y315703D01*
X987490Y315570D01*
X986891Y315171D01*
X986492Y314239D01*
X986293Y313441D01*
Y312642D01*
X986492Y311844D01*
X986991Y311045D01*
X987590Y310513D01*
X988289Y310380D01*
X988988Y310646D01*
X989686Y311444D01*
G01X994577Y310380D02*
Y315703D01*
G01Y314639D02*
X995076Y315171D01*
X995575Y315570D01*
X996274Y315703D01*
X996773Y315570D01*
X997372Y315171D01*
G01X1010148Y307718D02*
Y315703D01*
G01Y314506D02*
X1010647Y315171D01*
X1011146Y315570D01*
X1011944Y315703D01*
X1012643Y315570D01*
X1013342Y314905D01*
X1013641Y313973D01*
X1013741Y313042D01*
X1013641Y312110D01*
X1013342Y311178D01*
X1012743Y310646D01*
X1011944Y310380D01*
X1011246Y310513D01*
X1010547Y310912D01*
X1010148Y311444D01*
G01X1019929Y310380D02*
Y318365D01*
G01X1029711Y310380D02*
Y315703D01*
G01Y314772D02*
X1029312Y315304D01*
X1028713Y315570D01*
X1028014Y315703D01*
X1027316Y315437D01*
X1026717Y314905D01*
X1026317Y314106D01*
X1026118Y313042D01*
X1026317Y311977D01*
X1026717Y311178D01*
X1027316Y310646D01*
X1028014Y310380D01*
X1028713Y310513D01*
X1029312Y310912D01*
X1029711Y311444D01*
G01X1035899Y318365D02*
Y310380D01*
G01X1034502Y315703D02*
X1037297D01*
G01X1043884D02*
Y310380D01*
G01Y317833D02*
X1043685Y317966D01*
Y318232D01*
X1043884Y318365D01*
X1044084Y318232D01*
Y317966D01*
X1043884Y317833D01*
G01X1050173Y310380D02*
Y315703D01*
G01Y314372D02*
X1050572Y315038D01*
X1051171Y315570D01*
X1051969Y315703D01*
X1052668Y315570D01*
X1053267Y315038D01*
X1053566Y314106D01*
Y310380D01*
G01X1058457Y308384D02*
X1059156Y307851D01*
X1059954Y307718D01*
X1060653Y307851D01*
X1061252Y308517D01*
X1061651Y309448D01*
Y315703D01*
G01Y314639D02*
X1061252Y315171D01*
X1060653Y315570D01*
X1059954Y315703D01*
X1059156Y315437D01*
X1058657Y314905D01*
X1058257Y313973D01*
X1058058Y313042D01*
X1058158Y312243D01*
X1058557Y311311D01*
X1059156Y310646D01*
X1059954Y310380D01*
X1060553Y310513D01*
X1061252Y311045D01*
X1061651Y311577D01*
G01X1068339Y307718D02*
X1069337Y309049D01*
X1069836Y310380D01*
Y315703D01*
X1069337Y317034D01*
X1068339Y318365D01*
G01X738458Y335380D02*
Y343365D01*
X740854D01*
X741652Y342966D01*
X742251Y342034D01*
X742451Y340970D01*
X742251Y339905D01*
X741752Y339106D01*
X740854Y338707D01*
X738458D01*
G01X748439Y335380D02*
Y343365D01*
G01X754728Y340703D02*
Y336977D01*
X755127Y336045D01*
X755726Y335513D01*
X756424Y335380D01*
X757123Y335513D01*
X757722Y336045D01*
X758121Y336977D01*
G01Y335380D02*
Y340703D01*
G01X763012Y333384D02*
X763711Y332851D01*
X764509Y332718D01*
X765208Y332851D01*
X765807Y333517D01*
X766206Y334448D01*
Y340703D01*
G01Y339639D02*
X765807Y340171D01*
X765208Y340570D01*
X764509Y340703D01*
X763711Y340437D01*
X763212Y339905D01*
X762812Y338973D01*
X762613Y338042D01*
X762713Y337243D01*
X763112Y336311D01*
X763711Y335646D01*
X764509Y335380D01*
X765108Y335513D01*
X765807Y336045D01*
X766206Y336577D01*
G01X770997Y333384D02*
X771696Y332851D01*
X772494Y332718D01*
X773193Y332851D01*
X773792Y333517D01*
X774191Y334448D01*
Y340703D01*
G01Y339639D02*
X773792Y340171D01*
X773193Y340570D01*
X772494Y340703D01*
X771696Y340437D01*
X771197Y339905D01*
X770797Y338973D01*
X770598Y338042D01*
X770698Y337243D01*
X771097Y336311D01*
X771696Y335646D01*
X772494Y335380D01*
X773093Y335513D01*
X773792Y336045D01*
X774191Y336577D01*
G01X778882Y338973D02*
X782076D01*
X781777Y339905D01*
X781278Y340437D01*
X780579Y340703D01*
X779880Y340570D01*
X779281Y340171D01*
X778882Y339239D01*
X778683Y338441D01*
Y337642D01*
X778882Y336844D01*
X779381Y336045D01*
X779980Y335513D01*
X780679Y335380D01*
X781378Y335646D01*
X782076Y336444D01*
G01X790161Y343365D02*
Y335380D01*
G01Y336577D02*
X789762Y335912D01*
X789163Y335513D01*
X788464Y335380D01*
X787666Y335646D01*
X787067Y336311D01*
X786668Y337110D01*
X786568Y338042D01*
X786668Y338973D01*
X787067Y339772D01*
X787666Y340437D01*
X788464Y340703D01*
X789163Y340570D01*
X789662Y340304D01*
X790161Y339772D01*
G01X801839Y343365D02*
X804334Y335380D01*
X806830Y343365D01*
G01X812319Y340703D02*
Y335380D01*
G01Y342833D02*
X812120Y342966D01*
Y343232D01*
X812319Y343365D01*
X812519Y343232D01*
Y342966D01*
X812319Y342833D01*
G01X822101Y335380D02*
Y340703D01*
G01Y339772D02*
X821702Y340304D01*
X821103Y340570D01*
X820404Y340703D01*
X819706Y340437D01*
X819107Y339905D01*
X818707Y339106D01*
X818508Y338042D01*
X818707Y336977D01*
X819107Y336178D01*
X819706Y335646D01*
X820404Y335380D01*
X821103Y335513D01*
X821702Y335912D01*
X822101Y336444D01*
G01X827790Y332718D02*
X826792Y334049D01*
X826293Y335380D01*
Y340703D01*
X826792Y342034D01*
X827790Y343365D01*
G01X834578Y335380D02*
Y343365D01*
G01Y339506D02*
X835077Y340171D01*
X835576Y340570D01*
X836374Y340703D01*
X836973Y340570D01*
X837672Y340038D01*
X837971Y339239D01*
Y335380D01*
G01X844259D02*
X843661Y335513D01*
X843062Y336045D01*
X842662Y336977D01*
X842463Y338042D01*
X842662Y339106D01*
X843062Y340038D01*
X843661Y340570D01*
X844259Y340703D01*
X844858Y340570D01*
X845457Y340038D01*
X845856Y339106D01*
X845956Y338042D01*
X845856Y336977D01*
X845457Y336045D01*
X844858Y335513D01*
X844259Y335380D01*
G01X852244D02*
Y343365D01*
G01X858732Y338973D02*
X861926D01*
X861627Y339905D01*
X861128Y340437D01*
X860429Y340703D01*
X859730Y340570D01*
X859131Y340171D01*
X858732Y339239D01*
X858533Y338441D01*
Y337642D01*
X858732Y336844D01*
X859231Y336045D01*
X859830Y335513D01*
X860529Y335380D01*
X861228Y335646D01*
X861926Y336444D01*
G01X874702Y336311D02*
X875201Y335779D01*
X875900Y335380D01*
X876499D01*
X877098Y335646D01*
X877497Y336045D01*
X877697Y336577D01*
X877597Y337376D01*
X877198Y337775D01*
X875401Y338574D01*
X875002Y339506D01*
X875201Y340171D01*
X875601Y340570D01*
X876199Y340703D01*
X876798Y340570D01*
X877397Y340171D01*
G01X884184Y340703D02*
Y335380D01*
G01Y342833D02*
X883985Y342966D01*
Y343232D01*
X884184Y343365D01*
X884384Y343232D01*
Y342966D01*
X884184Y342833D01*
G01X890672Y340703D02*
X893667D01*
X890672Y335380D01*
X893667D01*
G01X898657Y338973D02*
X901851D01*
X901552Y339905D01*
X901053Y340437D01*
X900354Y340703D01*
X899655Y340570D01*
X899056Y340171D01*
X898657Y339239D01*
X898458Y338441D01*
Y337642D01*
X898657Y336844D01*
X899156Y336045D01*
X899755Y335513D01*
X900454Y335380D01*
X901153Y335646D01*
X901851Y336444D01*
G01X910136Y335380D02*
X906143Y338042D01*
X910136Y340703D01*
G01X916124Y335380D02*
Y343365D01*
X914927Y341768D01*
G01Y335380D02*
X917322D01*
G01X922213Y338707D02*
X922912Y339639D01*
X923511Y340171D01*
X924309Y340437D01*
X925008Y340171D01*
X925507Y339639D01*
X925906Y338840D01*
X926006Y337909D01*
X925906Y337110D01*
X925507Y336311D01*
X924908Y335646D01*
X924209Y335380D01*
X923411Y335646D01*
X922712Y336444D01*
X922313Y337642D01*
X922213Y338973D01*
X922413Y340703D01*
X922712Y341635D01*
X923211Y342566D01*
X923910Y343232D01*
X924609Y343365D01*
X925307Y343099D01*
X925806Y342433D01*
G01X937085Y335380D02*
Y340703D01*
G01Y339239D02*
X937384Y339905D01*
X937884Y340437D01*
X938582Y340703D01*
X939281Y340437D01*
X939780Y339905D01*
X940079Y339239D01*
Y335380D01*
G01Y339239D02*
X940379Y339905D01*
X940878Y340437D01*
X941577Y340703D01*
X942275Y340437D01*
X942775Y339905D01*
X943074Y339106D01*
Y335380D01*
G01X948064Y340703D02*
Y335380D01*
G01Y342833D02*
X947865Y342966D01*
Y343232D01*
X948064Y343365D01*
X948264Y343232D01*
Y342966D01*
X948064Y342833D01*
G01X956049Y335380D02*
Y343365D01*
G01X964534Y332718D02*
X965532Y334049D01*
X966031Y335380D01*
Y340703D01*
X965532Y342034D01*
X964534Y343365D01*
G01X738458Y322880D02*
Y330865D01*
X740854D01*
X741652Y330466D01*
X742251Y329534D01*
X742451Y328470D01*
X742251Y327405D01*
X741752Y326606D01*
X740854Y326207D01*
X738458D01*
G01X748439Y322880D02*
Y330865D01*
G01X754728Y328203D02*
Y324477D01*
X755127Y323545D01*
X755726Y323013D01*
X756424Y322880D01*
X757123Y323013D01*
X757722Y323545D01*
X758121Y324477D01*
G01Y322880D02*
Y328203D01*
G01X763012Y320884D02*
X763711Y320351D01*
X764509Y320218D01*
X765208Y320351D01*
X765807Y321017D01*
X766206Y321948D01*
Y328203D01*
G01Y327139D02*
X765807Y327671D01*
X765208Y328070D01*
X764509Y328203D01*
X763711Y327937D01*
X763212Y327405D01*
X762812Y326473D01*
X762613Y325542D01*
X762713Y324743D01*
X763112Y323811D01*
X763711Y323146D01*
X764509Y322880D01*
X765108Y323013D01*
X765807Y323545D01*
X766206Y324077D01*
G01X770997Y320884D02*
X771696Y320351D01*
X772494Y320218D01*
X773193Y320351D01*
X773792Y321017D01*
X774191Y321948D01*
Y328203D01*
G01Y327139D02*
X773792Y327671D01*
X773193Y328070D01*
X772494Y328203D01*
X771696Y327937D01*
X771197Y327405D01*
X770797Y326473D01*
X770598Y325542D01*
X770698Y324743D01*
X771097Y323811D01*
X771696Y323146D01*
X772494Y322880D01*
X773093Y323013D01*
X773792Y323545D01*
X774191Y324077D01*
G01X778882Y326473D02*
X782076D01*
X781777Y327405D01*
X781278Y327937D01*
X780579Y328203D01*
X779880Y328070D01*
X779281Y327671D01*
X778882Y326739D01*
X778683Y325941D01*
Y325142D01*
X778882Y324344D01*
X779381Y323545D01*
X779980Y323013D01*
X780679Y322880D01*
X781378Y323146D01*
X782076Y323944D01*
G01X790161Y330865D02*
Y322880D01*
G01Y324077D02*
X789762Y323412D01*
X789163Y323013D01*
X788464Y322880D01*
X787666Y323146D01*
X787067Y323811D01*
X786668Y324610D01*
X786568Y325542D01*
X786668Y326473D01*
X787067Y327272D01*
X787666Y327937D01*
X788464Y328203D01*
X789163Y328070D01*
X789662Y327804D01*
X790161Y327272D01*
G01X802338Y322880D02*
Y330865D01*
X804734D01*
X805532Y330466D01*
X806131Y329534D01*
X806331Y328470D01*
X806131Y327405D01*
X805632Y326606D01*
X804734Y326207D01*
X802338D01*
G01X812319Y330865D02*
Y322880D01*
G01X810024Y330865D02*
X814615D01*
G01X818208Y322880D02*
Y330865D01*
G01X822401D02*
Y322880D01*
G01Y326872D02*
X818208D01*
G01X827790Y320218D02*
X826792Y321549D01*
X826293Y322880D01*
Y328203D01*
X826792Y329534D01*
X827790Y330865D01*
G01X834578Y322880D02*
Y330865D01*
G01Y327006D02*
X835077Y327671D01*
X835576Y328070D01*
X836374Y328203D01*
X836973Y328070D01*
X837672Y327538D01*
X837971Y326739D01*
Y322880D01*
G01X844259D02*
X843661Y323013D01*
X843062Y323545D01*
X842662Y324477D01*
X842463Y325542D01*
X842662Y326606D01*
X843062Y327538D01*
X843661Y328070D01*
X844259Y328203D01*
X844858Y328070D01*
X845457Y327538D01*
X845856Y326606D01*
X845956Y325542D01*
X845856Y324477D01*
X845457Y323545D01*
X844858Y323013D01*
X844259Y322880D01*
G01X852244D02*
Y330865D01*
G01X858732Y326473D02*
X861926D01*
X861627Y327405D01*
X861128Y327937D01*
X860429Y328203D01*
X859730Y328070D01*
X859131Y327671D01*
X858732Y326739D01*
X858533Y325941D01*
Y325142D01*
X858732Y324344D01*
X859231Y323545D01*
X859830Y323013D01*
X860529Y322880D01*
X861228Y323146D01*
X861926Y323944D01*
G01X874702Y323811D02*
X875201Y323279D01*
X875900Y322880D01*
X876499D01*
X877098Y323146D01*
X877497Y323545D01*
X877697Y324077D01*
X877597Y324876D01*
X877198Y325275D01*
X875401Y326074D01*
X875002Y327006D01*
X875201Y327671D01*
X875601Y328070D01*
X876199Y328203D01*
X876798Y328070D01*
X877397Y327671D01*
G01X884184Y328203D02*
Y322880D01*
G01Y330333D02*
X883985Y330466D01*
Y330732D01*
X884184Y330865D01*
X884384Y330732D01*
Y330466D01*
X884184Y330333D01*
G01X890672Y328203D02*
X893667D01*
X890672Y322880D01*
X893667D01*
G01X898657Y326473D02*
X901851D01*
X901552Y327405D01*
X901053Y327937D01*
X900354Y328203D01*
X899655Y328070D01*
X899056Y327671D01*
X898657Y326739D01*
X898458Y325941D01*
Y325142D01*
X898657Y324344D01*
X899156Y323545D01*
X899755Y323013D01*
X900454Y322880D01*
X901153Y323146D01*
X901851Y323944D01*
G01X906143Y322880D02*
X910136Y325542D01*
X906143Y328203D01*
G01X914827Y324344D02*
X917422D01*
G01Y326739D02*
X914827D01*
G01X924109Y322880D02*
Y330865D01*
X922912Y329268D01*
G01Y322880D02*
X925307D01*
G01X930198Y326207D02*
X930897Y327139D01*
X931496Y327671D01*
X932294Y327937D01*
X932993Y327671D01*
X933492Y327139D01*
X933891Y326340D01*
X933991Y325409D01*
X933891Y324610D01*
X933492Y323811D01*
X932893Y323146D01*
X932194Y322880D01*
X931396Y323146D01*
X930697Y323944D01*
X930298Y325142D01*
X930198Y326473D01*
X930398Y328203D01*
X930697Y329135D01*
X931196Y330066D01*
X931895Y330732D01*
X932594Y330865D01*
X933292Y330599D01*
X933791Y329933D01*
G01X945070Y322880D02*
Y328203D01*
G01Y326739D02*
X945369Y327405D01*
X945869Y327937D01*
X946567Y328203D01*
X947266Y327937D01*
X947765Y327405D01*
X948064Y326739D01*
Y322880D01*
G01Y326739D02*
X948364Y327405D01*
X948863Y327937D01*
X949562Y328203D01*
X950260Y327937D01*
X950760Y327405D01*
X951059Y326606D01*
Y322880D01*
G01X956049Y328203D02*
Y322880D01*
G01Y330333D02*
X955850Y330466D01*
Y330732D01*
X956049Y330865D01*
X956249Y330732D01*
Y330466D01*
X956049Y330333D01*
G01X964034Y322880D02*
Y330865D01*
G01X972519Y320218D02*
X973517Y321549D01*
X974016Y322880D01*
Y328203D01*
X973517Y329534D01*
X972519Y330865D01*
G01X752954Y355865D02*
Y347880D01*
G01X751557Y353203D02*
X754352D01*
G01X759243Y347880D02*
Y355865D01*
G01Y352006D02*
X759742Y352671D01*
X760241Y353070D01*
X761039Y353203D01*
X761638Y353070D01*
X762337Y352538D01*
X762636Y351739D01*
Y347880D01*
G01X767427Y351473D02*
X770621D01*
X770322Y352405D01*
X769823Y352937D01*
X769124Y353203D01*
X768425Y353070D01*
X767826Y352671D01*
X767427Y351739D01*
X767228Y350941D01*
Y350142D01*
X767427Y349344D01*
X767926Y348545D01*
X768525Y348013D01*
X769224Y347880D01*
X769923Y348146D01*
X770621Y348944D01*
G01X783497Y347880D02*
Y353203D01*
G01Y352139D02*
X783996Y352671D01*
X784495Y353070D01*
X785194Y353203D01*
X785693Y353070D01*
X786292Y352671D01*
G01X791382Y351473D02*
X794576D01*
X794277Y352405D01*
X793778Y352937D01*
X793079Y353203D01*
X792380Y353070D01*
X791781Y352671D01*
X791382Y351739D01*
X791183Y350941D01*
Y350142D01*
X791382Y349344D01*
X791881Y348545D01*
X792480Y348013D01*
X793179Y347880D01*
X793878Y348146D01*
X794576Y348944D01*
G01X800864Y347880D02*
Y355865D01*
G01X810646Y347880D02*
Y353203D01*
G01Y352272D02*
X810247Y352804D01*
X809648Y353070D01*
X808949Y353203D01*
X808251Y352937D01*
X807652Y352405D01*
X807252Y351606D01*
X807053Y350542D01*
X807252Y349477D01*
X807652Y348678D01*
X808251Y348146D01*
X808949Y347880D01*
X809648Y348013D01*
X810247Y348412D01*
X810646Y348944D01*
G01X816834Y355865D02*
Y347880D01*
G01X815437Y353203D02*
X818232D01*
G01X824819D02*
Y347880D01*
G01Y355333D02*
X824620Y355466D01*
Y355732D01*
X824819Y355865D01*
X825019Y355732D01*
Y355466D01*
X824819Y355333D01*
G01X831008Y353203D02*
X832804Y347880D01*
X834601Y353203D01*
G01X839292Y351473D02*
X842486D01*
X842187Y352405D01*
X841688Y352937D01*
X840989Y353203D01*
X840290Y353070D01*
X839691Y352671D01*
X839292Y351739D01*
X839093Y350941D01*
Y350142D01*
X839292Y349344D01*
X839791Y348545D01*
X840390Y348013D01*
X841089Y347880D01*
X841788Y348146D01*
X842486Y348944D01*
G01X856759Y347880D02*
Y355865D01*
G01X864744Y347880D02*
X864146Y348013D01*
X863547Y348545D01*
X863147Y349477D01*
X862948Y350542D01*
X863147Y351606D01*
X863547Y352538D01*
X864146Y353070D01*
X864744Y353203D01*
X865343Y353070D01*
X865942Y352538D01*
X866341Y351606D01*
X866441Y350542D01*
X866341Y349477D01*
X865942Y348545D01*
X865343Y348013D01*
X864744Y347880D01*
G01X874326Y352538D02*
X873628Y353070D01*
X873029Y353203D01*
X872230Y352937D01*
X871631Y352405D01*
X871232Y351473D01*
X871132Y350542D01*
X871232Y349610D01*
X871631Y348811D01*
X872230Y348146D01*
X873029Y347880D01*
X873728Y348146D01*
X874326Y348678D01*
G01X882511Y347880D02*
Y353203D01*
G01Y352272D02*
X882112Y352804D01*
X881513Y353070D01*
X880814Y353203D01*
X880116Y352937D01*
X879517Y352405D01*
X879117Y351606D01*
X878918Y350542D01*
X879117Y349477D01*
X879517Y348678D01*
X880116Y348146D01*
X880814Y347880D01*
X881513Y348013D01*
X882112Y348412D01*
X882511Y348944D01*
G01X888699Y355865D02*
Y347880D01*
G01X887302Y353203D02*
X890097D01*
G01X896684D02*
Y347880D01*
G01Y355333D02*
X896485Y355466D01*
Y355732D01*
X896684Y355865D01*
X896884Y355732D01*
Y355466D01*
X896684Y355333D01*
G01X904669Y347880D02*
X904071Y348013D01*
X903472Y348545D01*
X903072Y349477D01*
X902873Y350542D01*
X903072Y351606D01*
X903472Y352538D01*
X904071Y353070D01*
X904669Y353203D01*
X905268Y353070D01*
X905867Y352538D01*
X906266Y351606D01*
X906366Y350542D01*
X906266Y349477D01*
X905867Y348545D01*
X905268Y348013D01*
X904669Y347880D01*
G01X910958D02*
Y353203D01*
G01Y351872D02*
X911357Y352538D01*
X911956Y353070D01*
X912754Y353203D01*
X913453Y353070D01*
X914052Y352538D01*
X914351Y351606D01*
Y347880D01*
G01X928624D02*
X928026Y348013D01*
X927427Y348545D01*
X927027Y349477D01*
X926828Y350542D01*
X927027Y351606D01*
X927427Y352538D01*
X928026Y353070D01*
X928624Y353203D01*
X929223Y353070D01*
X929822Y352538D01*
X930221Y351606D01*
X930321Y350542D01*
X930221Y349477D01*
X929822Y348545D01*
X929223Y348013D01*
X928624Y347880D01*
G01X936011D02*
Y354667D01*
X936210Y355333D01*
X936609Y355732D01*
X937208Y355865D01*
X937807Y355599D01*
X938107Y354933D01*
G01X936909Y352671D02*
X934913D01*
G01X950883Y347880D02*
Y355865D01*
G01Y352006D02*
X951382Y352671D01*
X951881Y353070D01*
X952679Y353203D01*
X953278Y353070D01*
X953977Y352538D01*
X954276Y351739D01*
Y347880D01*
G01X960564D02*
X959966Y348013D01*
X959367Y348545D01*
X958967Y349477D01*
X958768Y350542D01*
X958967Y351606D01*
X959367Y352538D01*
X959966Y353070D01*
X960564Y353203D01*
X961163Y353070D01*
X961762Y352538D01*
X962161Y351606D01*
X962261Y350542D01*
X962161Y349477D01*
X961762Y348545D01*
X961163Y348013D01*
X960564Y347880D01*
G01X968549D02*
Y355865D01*
G01X975037Y351473D02*
X978231D01*
X977932Y352405D01*
X977433Y352937D01*
X976734Y353203D01*
X976035Y353070D01*
X975436Y352671D01*
X975037Y351739D01*
X974838Y350941D01*
Y350142D01*
X975037Y349344D01*
X975536Y348545D01*
X976135Y348013D01*
X976834Y347880D01*
X977533Y348146D01*
X978231Y348944D01*
G01X992504Y355865D02*
Y347880D01*
G01X991107Y353203D02*
X993902D01*
G01X1000489Y347880D02*
X999891Y348013D01*
X999292Y348545D01*
X998892Y349477D01*
X998693Y350542D01*
X998892Y351606D01*
X999292Y352538D01*
X999891Y353070D01*
X1000489Y353203D01*
X1001088Y353070D01*
X1001687Y352538D01*
X1002086Y351606D01*
X1002186Y350542D01*
X1002086Y349477D01*
X1001687Y348545D01*
X1001088Y348013D01*
X1000489Y347880D01*
G01X1014763D02*
Y355865D01*
G01Y352006D02*
X1015262Y352671D01*
X1015761Y353070D01*
X1016559Y353203D01*
X1017158Y353070D01*
X1017857Y352538D01*
X1018156Y351739D01*
Y347880D01*
G01X1024444D02*
X1023846Y348013D01*
X1023247Y348545D01*
X1022847Y349477D01*
X1022648Y350542D01*
X1022847Y351606D01*
X1023247Y352538D01*
X1023846Y353070D01*
X1024444Y353203D01*
X1025043Y353070D01*
X1025642Y352538D01*
X1026041Y351606D01*
X1026141Y350542D01*
X1026041Y349477D01*
X1025642Y348545D01*
X1025043Y348013D01*
X1024444Y347880D01*
G01X1032429D02*
Y355865D01*
G01X1038917Y351473D02*
X1042111D01*
X1041812Y352405D01*
X1041313Y352937D01*
X1040614Y353203D01*
X1039915Y353070D01*
X1039316Y352671D01*
X1038917Y351739D01*
X1038718Y350941D01*
Y350142D01*
X1038917Y349344D01*
X1039416Y348545D01*
X1040015Y348013D01*
X1040714Y347880D01*
X1041413Y348146D01*
X1042111Y348944D01*
G01X899257Y370365D02*
X901652D01*
G01X900454D02*
Y362380D01*
G01X899257D02*
X901652D01*
G01X908439Y370365D02*
Y362380D01*
G01X907042Y367703D02*
X909837D01*
G01X914927Y365973D02*
X918121D01*
X917822Y366905D01*
X917323Y367437D01*
X916624Y367703D01*
X915925Y367570D01*
X915326Y367171D01*
X914927Y366239D01*
X914728Y365441D01*
Y364642D01*
X914927Y363844D01*
X915426Y363045D01*
X916025Y362513D01*
X916724Y362380D01*
X917423Y362646D01*
X918121Y363444D01*
G01X921415Y362380D02*
Y367703D01*
G01Y366239D02*
X921714Y366905D01*
X922214Y367437D01*
X922912Y367703D01*
X923611Y367437D01*
X924110Y366905D01*
X924409Y366239D01*
Y362380D01*
G01Y366239D02*
X924709Y366905D01*
X925208Y367437D01*
X925907Y367703D01*
X926605Y367437D01*
X927105Y366905D01*
X927404Y366106D01*
Y362380D01*
G01X930897Y363311D02*
X931396Y362779D01*
X932095Y362380D01*
X932694D01*
X933293Y362646D01*
X933692Y363045D01*
X933892Y363577D01*
X933792Y364376D01*
X933393Y364775D01*
X931596Y365574D01*
X931197Y366506D01*
X931396Y367171D01*
X931796Y367570D01*
X932394Y367703D01*
X932993Y367570D01*
X933592Y367171D01*
G01X1195054Y210280D02*
Y218265D01*
X1193857Y216668D01*
G01Y210280D02*
X1196252D01*
G01X1203039Y210014D02*
X1202840Y210147D01*
Y210413D01*
X1203039Y210546D01*
X1203239Y210413D01*
Y210147D01*
X1203039Y210014D01*
G01X1211024Y218265D02*
X1210226Y217999D01*
X1209627Y217333D01*
X1209228Y216535D01*
X1208928Y215470D01*
X1208829Y214272D01*
X1208928Y213075D01*
X1209228Y212010D01*
X1209627Y211211D01*
X1210226Y210546D01*
X1211024Y210280D01*
X1211823Y210546D01*
X1212422Y211211D01*
X1212821Y212010D01*
X1213121Y213075D01*
X1213220Y214272D01*
X1213121Y215470D01*
X1212821Y216535D01*
X1212422Y217333D01*
X1211823Y217999D01*
X1211024Y218265D01*
G01X1216015Y210280D02*
Y215603D01*
G01Y214139D02*
X1216314Y214805D01*
X1216814Y215337D01*
X1217512Y215603D01*
X1218211Y215337D01*
X1218710Y214805D01*
X1219009Y214139D01*
Y210280D01*
G01Y214139D02*
X1219309Y214805D01*
X1219808Y215337D01*
X1220507Y215603D01*
X1221205Y215337D01*
X1221705Y214805D01*
X1222004Y214006D01*
Y210280D01*
G01X1226994Y215603D02*
Y210280D01*
G01Y217733D02*
X1226795Y217866D01*
Y218132D01*
X1226994Y218265D01*
X1227194Y218132D01*
Y217866D01*
X1226994Y217733D01*
G01X1234979Y210280D02*
Y218265D01*
G01X1247955Y210280D02*
Y215603D01*
G01Y214139D02*
X1248254Y214805D01*
X1248754Y215337D01*
X1249452Y215603D01*
X1250151Y215337D01*
X1250650Y214805D01*
X1250949Y214139D01*
Y210280D01*
G01Y214139D02*
X1251249Y214805D01*
X1251748Y215337D01*
X1252447Y215603D01*
X1253145Y215337D01*
X1253645Y214805D01*
X1253944Y214006D01*
Y210280D01*
G01X1260731D02*
Y215603D01*
G01Y214672D02*
X1260332Y215204D01*
X1259733Y215470D01*
X1259034Y215603D01*
X1258336Y215337D01*
X1257737Y214805D01*
X1257337Y214006D01*
X1257138Y212942D01*
X1257337Y211877D01*
X1257737Y211078D01*
X1258336Y210546D01*
X1259034Y210280D01*
X1259733Y210413D01*
X1260332Y210812D01*
X1260731Y211344D01*
G01X1265422Y215603D02*
X1268417Y210280D01*
G01Y215603D02*
X1265422Y210280D01*
G01X1195693Y225242D02*
X1198089D01*
G01X1196791Y226972D02*
Y223511D01*
G01X1202980Y222314D02*
X1206573Y230565D01*
G01X1211464Y225242D02*
X1214059D01*
G01X1218551Y223777D02*
X1219149Y223112D01*
X1219848Y222713D01*
X1220746Y222580D01*
X1221645Y222846D01*
X1222343Y223378D01*
X1222843Y224310D01*
X1222942Y225375D01*
X1222743Y226439D01*
X1222244Y227105D01*
X1221545Y227637D01*
X1220846Y227770D01*
X1220148Y227637D01*
X1219249Y227105D01*
X1219549Y230565D01*
X1222244D01*
G01X1225737Y222580D02*
Y227903D01*
G01Y226439D02*
X1226036Y227105D01*
X1226536Y227637D01*
X1227234Y227903D01*
X1227933Y227637D01*
X1228432Y227105D01*
X1228731Y226439D01*
Y222580D01*
G01Y226439D02*
X1229031Y227105D01*
X1229530Y227637D01*
X1230229Y227903D01*
X1230927Y227637D01*
X1231427Y227105D01*
X1231726Y226306D01*
Y222580D01*
G01X1236716Y227903D02*
Y222580D01*
G01Y230033D02*
X1236517Y230166D01*
Y230432D01*
X1236716Y230565D01*
X1236916Y230432D01*
Y230166D01*
X1236716Y230033D01*
G01X1244701Y222580D02*
Y230565D01*
G01X1195693Y238242D02*
X1198089D01*
G01X1196791Y239972D02*
Y236511D01*
G01X1202980Y235314D02*
X1206573Y243565D01*
G01X1211464Y238242D02*
X1214059D01*
G01X1218551Y236777D02*
X1219149Y236112D01*
X1219848Y235713D01*
X1220746Y235580D01*
X1221645Y235846D01*
X1222343Y236378D01*
X1222843Y237310D01*
X1222942Y238375D01*
X1222743Y239439D01*
X1222244Y240105D01*
X1221545Y240637D01*
X1220846Y240770D01*
X1220148Y240637D01*
X1219249Y240105D01*
X1219549Y243565D01*
X1222244D01*
G01X1225737Y235580D02*
Y240903D01*
G01Y239439D02*
X1226036Y240105D01*
X1226536Y240637D01*
X1227234Y240903D01*
X1227933Y240637D01*
X1228432Y240105D01*
X1228731Y239439D01*
Y235580D01*
G01Y239439D02*
X1229031Y240105D01*
X1229530Y240637D01*
X1230229Y240903D01*
X1230927Y240637D01*
X1231427Y240105D01*
X1231726Y239306D01*
Y235580D01*
G01X1236716Y240903D02*
Y235580D01*
G01Y243033D02*
X1236517Y243166D01*
Y243432D01*
X1236716Y243565D01*
X1236916Y243432D01*
Y243166D01*
X1236716Y243033D01*
G01X1244701Y235580D02*
Y243565D01*
G01X1195693Y250742D02*
X1198089D01*
G01X1196791Y252472D02*
Y249011D01*
G01X1202980Y247814D02*
X1206573Y256065D01*
G01X1211464Y250742D02*
X1214059D01*
G01X1218850Y254734D02*
X1219449Y255533D01*
X1220148Y255932D01*
X1220946Y256065D01*
X1221944Y255799D01*
X1222643Y255133D01*
X1222843Y254335D01*
X1222743Y253536D01*
X1222343Y252871D01*
X1220347Y251540D01*
X1219449Y250609D01*
X1218850Y249277D01*
X1218650Y248080D01*
X1222843D01*
G01X1225737D02*
Y253403D01*
G01Y251939D02*
X1226036Y252605D01*
X1226536Y253137D01*
X1227234Y253403D01*
X1227933Y253137D01*
X1228432Y252605D01*
X1228731Y251939D01*
Y248080D01*
G01Y251939D02*
X1229031Y252605D01*
X1229530Y253137D01*
X1230229Y253403D01*
X1230927Y253137D01*
X1231427Y252605D01*
X1231726Y251806D01*
Y248080D01*
G01X1236716Y253403D02*
Y248080D01*
G01Y255533D02*
X1236517Y255666D01*
Y255932D01*
X1236716Y256065D01*
X1236916Y255932D01*
Y255666D01*
X1236716Y255533D01*
G01X1244701Y248080D02*
Y256065D01*
G01X1195476Y262942D02*
X1197872D01*
G01X1196574Y264672D02*
Y261211D01*
G01X1202364Y261877D02*
X1202962Y260945D01*
X1203761Y260413D01*
X1204659Y260280D01*
X1205458Y260413D01*
X1206256Y261078D01*
X1206755Y261877D01*
X1206855Y262675D01*
X1206656Y263607D01*
X1205957Y264272D01*
X1205258Y264539D01*
X1204360D01*
G01X1205258D02*
X1205857Y264938D01*
X1206356Y265603D01*
X1206556Y266402D01*
X1206356Y267200D01*
X1205857Y267866D01*
X1204959Y268265D01*
X1204060Y268132D01*
X1203162Y267599D01*
G01X1210748Y260014D02*
X1214341Y268265D01*
G01X1219232Y262942D02*
X1221827D01*
G01X1228514Y268265D02*
X1227716Y267999D01*
X1227117Y267333D01*
X1226718Y266535D01*
X1226418Y265470D01*
X1226319Y264272D01*
X1226418Y263075D01*
X1226718Y262010D01*
X1227117Y261211D01*
X1227716Y260546D01*
X1228514Y260280D01*
X1229313Y260546D01*
X1229912Y261211D01*
X1230311Y262010D01*
X1230611Y263075D01*
X1230710Y264272D01*
X1230611Y265470D01*
X1230311Y266535D01*
X1229912Y267333D01*
X1229313Y267999D01*
X1228514Y268265D01*
G01X1233505Y260280D02*
Y265603D01*
G01Y264139D02*
X1233804Y264805D01*
X1234304Y265337D01*
X1235002Y265603D01*
X1235701Y265337D01*
X1236200Y264805D01*
X1236499Y264139D01*
Y260280D01*
G01Y264139D02*
X1236799Y264805D01*
X1237298Y265337D01*
X1237997Y265603D01*
X1238695Y265337D01*
X1239195Y264805D01*
X1239494Y264006D01*
Y260280D01*
G01X1244484Y265603D02*
Y260280D01*
G01Y267733D02*
X1244285Y267866D01*
Y268132D01*
X1244484Y268265D01*
X1244684Y268132D01*
Y267866D01*
X1244484Y267733D01*
G01X1252469Y260280D02*
Y268265D01*
G01X1195693Y275242D02*
X1198089D01*
G01X1196791Y276972D02*
Y273511D01*
G01X1202980Y272314D02*
X1206573Y280565D01*
G01X1211464Y275242D02*
X1214059D01*
G01X1218850Y279234D02*
X1219449Y280033D01*
X1220148Y280432D01*
X1220946Y280565D01*
X1221944Y280299D01*
X1222643Y279633D01*
X1222843Y278835D01*
X1222743Y278036D01*
X1222343Y277371D01*
X1220347Y276040D01*
X1219449Y275109D01*
X1218850Y273777D01*
X1218650Y272580D01*
X1222843D01*
G01X1225737D02*
Y277903D01*
G01Y276439D02*
X1226036Y277105D01*
X1226536Y277637D01*
X1227234Y277903D01*
X1227933Y277637D01*
X1228432Y277105D01*
X1228731Y276439D01*
Y272580D01*
G01Y276439D02*
X1229031Y277105D01*
X1229530Y277637D01*
X1230229Y277903D01*
X1230927Y277637D01*
X1231427Y277105D01*
X1231726Y276306D01*
Y272580D01*
G01X1236716Y277903D02*
Y272580D01*
G01Y280033D02*
X1236517Y280166D01*
Y280432D01*
X1236716Y280565D01*
X1236916Y280432D01*
Y280166D01*
X1236716Y280033D01*
G01X1244701Y272580D02*
Y280565D01*
G01X1195693Y287803D02*
X1198089D01*
G01X1196791Y289533D02*
Y286072D01*
G01X1202980Y284875D02*
X1206573Y293126D01*
G01X1211464Y287803D02*
X1214059D01*
G01X1218551Y286738D02*
X1219149Y285806D01*
X1219948Y285274D01*
X1220846Y285141D01*
X1221645Y285274D01*
X1222443Y285939D01*
X1222942Y286738D01*
X1223042Y287536D01*
X1222843Y288468D01*
X1222144Y289133D01*
X1221445Y289400D01*
X1220547D01*
G01X1221445D02*
X1222044Y289799D01*
X1222543Y290464D01*
X1222743Y291263D01*
X1222543Y292061D01*
X1222044Y292727D01*
X1221146Y293126D01*
X1220247Y292993D01*
X1219349Y292460D01*
G01X1225737Y285141D02*
Y290464D01*
G01Y289000D02*
X1226036Y289666D01*
X1226536Y290198D01*
X1227234Y290464D01*
X1227933Y290198D01*
X1228432Y289666D01*
X1228731Y289000D01*
Y285141D01*
G01Y289000D02*
X1229031Y289666D01*
X1229530Y290198D01*
X1230229Y290464D01*
X1230927Y290198D01*
X1231427Y289666D01*
X1231726Y288867D01*
Y285141D01*
G01X1236716Y290464D02*
Y285141D01*
G01Y292594D02*
X1236517Y292727D01*
Y292993D01*
X1236716Y293126D01*
X1236916Y292993D01*
Y292727D01*
X1236716Y292594D01*
G01X1244701Y285141D02*
Y293126D01*
G01X1194056Y300542D02*
X1196452D01*
G01X1195154Y302272D02*
Y298811D01*
G01X1201343Y297614D02*
X1204936Y305865D01*
G01X1209827Y300542D02*
X1212422D01*
G01X1217213Y304534D02*
X1217812Y305333D01*
X1218511Y305732D01*
X1219309Y305865D01*
X1220307Y305599D01*
X1221006Y304933D01*
X1221206Y304135D01*
X1221106Y303336D01*
X1220706Y302671D01*
X1218710Y301340D01*
X1217812Y300409D01*
X1217213Y299077D01*
X1217013Y297880D01*
X1221206D01*
G01X1224100D02*
Y303203D01*
G01Y301739D02*
X1224399Y302405D01*
X1224899Y302937D01*
X1225597Y303203D01*
X1226296Y302937D01*
X1226795Y302405D01*
X1227094Y301739D01*
Y297880D01*
G01Y301739D02*
X1227394Y302405D01*
X1227893Y302937D01*
X1228592Y303203D01*
X1229290Y302937D01*
X1229790Y302405D01*
X1230089Y301606D01*
Y297880D01*
G01X1235079Y303203D02*
Y297880D01*
G01Y305333D02*
X1234880Y305466D01*
Y305732D01*
X1235079Y305865D01*
X1235279Y305732D01*
Y305466D01*
X1235079Y305333D01*
G01X1243064Y297880D02*
Y305865D01*
G01X1195693Y313742D02*
X1198089D01*
G01X1196791Y315472D02*
Y312011D01*
G01X1204776Y311080D02*
Y319065D01*
X1203579Y317468D01*
G01Y311080D02*
X1205974D01*
G01X1210965Y310814D02*
X1214558Y319065D01*
G01X1219449Y313742D02*
X1222044D01*
G01X1226536Y312677D02*
X1227134Y311745D01*
X1227933Y311213D01*
X1228831Y311080D01*
X1229630Y311213D01*
X1230428Y311878D01*
X1230927Y312677D01*
X1231027Y313475D01*
X1230828Y314407D01*
X1230129Y315072D01*
X1229430Y315339D01*
X1228532D01*
G01X1229430D02*
X1230029Y315738D01*
X1230528Y316403D01*
X1230728Y317202D01*
X1230528Y318000D01*
X1230029Y318666D01*
X1229131Y319065D01*
X1228232Y318932D01*
X1227334Y318399D01*
G01X1233722Y311080D02*
Y316403D01*
G01Y314939D02*
X1234021Y315605D01*
X1234521Y316137D01*
X1235219Y316403D01*
X1235918Y316137D01*
X1236417Y315605D01*
X1236716Y314939D01*
Y311080D01*
G01Y314939D02*
X1237016Y315605D01*
X1237515Y316137D01*
X1238214Y316403D01*
X1238912Y316137D01*
X1239412Y315605D01*
X1239711Y314806D01*
Y311080D01*
G01X1244701Y316403D02*
Y311080D01*
G01Y318533D02*
X1244502Y318666D01*
Y318932D01*
X1244701Y319065D01*
X1244901Y318932D01*
Y318666D01*
X1244701Y318533D01*
G01X1252686Y311080D02*
Y319065D01*
G01X1195693Y338242D02*
X1198089D01*
G01X1196791Y339972D02*
Y336511D01*
G01X1202880Y342234D02*
X1203479Y343033D01*
X1204178Y343432D01*
X1204976Y343565D01*
X1205974Y343299D01*
X1206673Y342633D01*
X1206873Y341835D01*
X1206773Y341036D01*
X1206373Y340371D01*
X1204377Y339040D01*
X1203479Y338109D01*
X1202880Y336777D01*
X1202680Y335580D01*
X1206873D01*
G01X1210965Y335314D02*
X1214558Y343565D01*
G01X1219449Y338242D02*
X1222044D01*
G01X1229929Y335580D02*
Y343565D01*
X1226236Y337842D01*
X1231227D01*
G01X1233722Y335580D02*
Y340903D01*
G01Y339439D02*
X1234021Y340105D01*
X1234521Y340637D01*
X1235219Y340903D01*
X1235918Y340637D01*
X1236417Y340105D01*
X1236716Y339439D01*
Y335580D01*
G01Y339439D02*
X1237016Y340105D01*
X1237515Y340637D01*
X1238214Y340903D01*
X1238912Y340637D01*
X1239412Y340105D01*
X1239711Y339306D01*
Y335580D01*
G01X1244701Y340903D02*
Y335580D01*
G01Y343033D02*
X1244502Y343166D01*
Y343432D01*
X1244701Y343565D01*
X1244901Y343432D01*
Y343166D01*
X1244701Y343033D01*
G01X1252686Y335580D02*
Y343565D01*
G01X1195693Y325742D02*
X1198089D01*
G01X1196791Y327472D02*
Y324011D01*
G01X1202980Y322814D02*
X1206573Y331065D01*
G01X1211464Y325742D02*
X1214059D01*
G01X1218850Y329734D02*
X1219449Y330533D01*
X1220148Y330932D01*
X1220946Y331065D01*
X1221944Y330799D01*
X1222643Y330133D01*
X1222843Y329335D01*
X1222743Y328536D01*
X1222343Y327871D01*
X1220347Y326540D01*
X1219449Y325609D01*
X1218850Y324277D01*
X1218650Y323080D01*
X1222843D01*
G01X1225737D02*
Y328403D01*
G01Y326939D02*
X1226036Y327605D01*
X1226536Y328137D01*
X1227234Y328403D01*
X1227933Y328137D01*
X1228432Y327605D01*
X1228731Y326939D01*
Y323080D01*
G01Y326939D02*
X1229031Y327605D01*
X1229530Y328137D01*
X1230229Y328403D01*
X1230927Y328137D01*
X1231427Y327605D01*
X1231726Y326806D01*
Y323080D01*
G01X1236716Y328403D02*
Y323080D01*
G01Y330533D02*
X1236517Y330666D01*
Y330932D01*
X1236716Y331065D01*
X1236916Y330932D01*
Y330666D01*
X1236716Y330533D01*
G01X1244701Y323080D02*
Y331065D01*
G01X1195693Y350742D02*
X1198089D01*
G01X1196791Y352472D02*
Y349011D01*
G01X1202980Y347814D02*
X1206573Y356065D01*
G01X1211464Y350742D02*
X1214059D01*
G01X1218551Y349677D02*
X1219149Y348745D01*
X1219948Y348213D01*
X1220846Y348080D01*
X1221645Y348213D01*
X1222443Y348878D01*
X1222942Y349677D01*
X1223042Y350475D01*
X1222843Y351407D01*
X1222144Y352072D01*
X1221445Y352339D01*
X1220547D01*
G01X1221445D02*
X1222044Y352738D01*
X1222543Y353403D01*
X1222743Y354202D01*
X1222543Y355000D01*
X1222044Y355666D01*
X1221146Y356065D01*
X1220247Y355932D01*
X1219349Y355399D01*
G01X1225737Y348080D02*
Y353403D01*
G01Y351939D02*
X1226036Y352605D01*
X1226536Y353137D01*
X1227234Y353403D01*
X1227933Y353137D01*
X1228432Y352605D01*
X1228731Y351939D01*
Y348080D01*
G01Y351939D02*
X1229031Y352605D01*
X1229530Y353137D01*
X1230229Y353403D01*
X1230927Y353137D01*
X1231427Y352605D01*
X1231726Y351806D01*
Y348080D01*
G01X1236716Y353403D02*
Y348080D01*
G01Y355533D02*
X1236517Y355666D01*
Y355932D01*
X1236716Y356065D01*
X1236916Y355932D01*
Y355666D01*
X1236716Y355533D01*
G01X1244701Y348080D02*
Y356065D01*
G01X1196854Y370865D02*
Y362880D01*
G01X1194559Y370865D02*
X1199150D01*
G01X1204839Y362880D02*
X1204241Y363013D01*
X1203642Y363545D01*
X1203242Y364477D01*
X1203043Y365542D01*
X1203242Y366606D01*
X1203642Y367538D01*
X1204241Y368070D01*
X1204839Y368203D01*
X1205438Y368070D01*
X1206037Y367538D01*
X1206436Y366606D01*
X1206536Y365542D01*
X1206436Y364477D01*
X1206037Y363545D01*
X1205438Y363013D01*
X1204839Y362880D01*
G01X1212824D02*
Y370865D01*
G01X1219312Y366473D02*
X1222506D01*
X1222207Y367405D01*
X1221708Y367937D01*
X1221009Y368203D01*
X1220310Y368070D01*
X1219711Y367671D01*
X1219312Y366739D01*
X1219113Y365941D01*
Y365142D01*
X1219312Y364344D01*
X1219811Y363545D01*
X1220410Y363013D01*
X1221109Y362880D01*
X1221808Y363146D01*
X1222506Y363944D01*
G01X1227397Y362880D02*
Y368203D01*
G01Y367139D02*
X1227896Y367671D01*
X1228395Y368070D01*
X1229094Y368203D01*
X1229593Y368070D01*
X1230192Y367671D01*
G01X1238576Y362880D02*
Y368203D01*
G01Y367272D02*
X1238177Y367804D01*
X1237578Y368070D01*
X1236879Y368203D01*
X1236181Y367937D01*
X1235582Y367405D01*
X1235182Y366606D01*
X1234983Y365542D01*
X1235182Y364477D01*
X1235582Y363678D01*
X1236181Y363146D01*
X1236879Y362880D01*
X1237578Y363013D01*
X1238177Y363412D01*
X1238576Y363944D01*
G01X1243068Y362880D02*
Y368203D01*
G01Y366872D02*
X1243467Y367538D01*
X1244066Y368070D01*
X1244864Y368203D01*
X1245563Y368070D01*
X1246162Y367538D01*
X1246461Y366606D01*
Y362880D01*
G01X1254346Y367538D02*
X1253648Y368070D01*
X1253049Y368203D01*
X1252250Y367937D01*
X1251651Y367405D01*
X1251252Y366473D01*
X1251152Y365542D01*
X1251252Y364610D01*
X1251651Y363811D01*
X1252250Y363146D01*
X1253049Y362880D01*
X1253748Y363146D01*
X1254346Y363678D01*
G01X1259237Y366473D02*
X1262431D01*
X1262132Y367405D01*
X1261633Y367937D01*
X1260934Y368203D01*
X1260235Y368070D01*
X1259636Y367671D01*
X1259237Y366739D01*
X1259038Y365941D01*
Y365142D01*
X1259237Y364344D01*
X1259736Y363545D01*
X1260335Y363013D01*
X1261034Y362880D01*
X1261733Y363146D01*
X1262431Y363944D01*
G01X-72840Y937080D02*
Y68280D01*
X1468060D01*
Y937080D01*
X-72840D01*
G01Y518680D02*
X1468060D01*
G01X150660Y326680D02*
X90860D01*
X90760Y326780D01*
G01X150560Y366180D02*
X90660D01*
G01X112660Y305480D02*
Y326680D01*
X112560Y326780D01*
X108160Y322380D01*
G01X112860Y326580D02*
Y326480D01*
X116960Y322380D01*
G01X113660Y366180D02*
X113760D01*
X116860Y369280D01*
G01X113660Y366580D02*
X114060D01*
G01X113760Y386480D02*
Y366680D01*
X113460Y366380D01*
X110460Y369380D01*
G01X109233Y771477D02*
X109243Y759477D01*
G01X109233Y771477D02*
X133254Y747497D01*
X133260Y708180D01*
G01X109233Y771477D02*
X121233Y771487D01*
G01X126160Y267980D02*
X150760D01*
X150960Y268180D01*
X148560Y270580D01*
G01X138660Y241180D02*
X177560D01*
X177860Y241480D01*
X175260Y244080D01*
G01X150760Y268180D02*
Y267880D01*
X148860Y265980D01*
G01X157060Y268080D02*
Y267880D01*
X159560Y265380D01*
G01X172360Y267980D02*
X157160D01*
X157060Y268080D01*
X159660Y270680D01*
G01X156960Y310780D02*
Y261780D01*
X156860Y261680D01*
G01X150960Y310580D02*
Y261380D01*
X150860Y261280D01*
G01X150960Y385280D02*
Y457280D01*
G01X151260Y440080D02*
Y439980D01*
X153060Y438180D01*
G01X164760Y440080D02*
X151360D01*
X151160Y440280D01*
X153260Y442380D01*
G01X155140Y779220D02*
X179140Y803220D01*
X211140D01*
G01X155140Y779220D02*
Y791220D01*
G01Y779220D02*
X167140D01*
G01X177860Y273580D02*
Y225980D01*
G01X177760Y241180D02*
X177560D01*
X174960Y238580D01*
G01X166680Y752650D02*
X174680Y744650D01*
G01X166680Y752650D02*
X208680D01*
G01X166680D02*
X174680Y760650D01*
G01X202860Y274080D02*
Y226080D01*
G01X202960Y241580D02*
Y241480D01*
X206160Y238280D01*
G01X234160Y241480D02*
X203060D01*
X202860Y241680D01*
X205860Y244680D01*
G01X202860Y273580D02*
X297260D01*
X297860Y272980D01*
G01X201860Y419780D02*
X291160D01*
X291660Y420280D01*
G01X209060Y440280D02*
X229960D01*
X230160Y440480D01*
X227360Y443280D01*
X227260D01*
G01X230060Y382180D02*
Y454680D01*
X230160Y454780D01*
G01X230060Y440380D02*
Y440280D01*
X227460Y437680D01*
G01X255860Y274080D02*
X256060D01*
X259660Y277680D01*
G01X255760Y273980D02*
X255260D01*
X251360Y277880D01*
G01X255660Y327880D02*
Y274180D01*
X255060Y273580D01*
G01X254560Y419180D02*
Y367980D01*
X255060Y367480D01*
G01X254560Y419580D02*
X257760Y416380D01*
G01X254460Y419680D02*
X251060Y416280D01*
G01X570360Y937180D02*
Y68280D01*
G01X593460Y375380D02*
Y207880D01*
G01D02*
X1189160D01*
Y375380D01*
X1272960D01*
Y357880D01*
G01X1189160Y207880D02*
X1272960D01*
Y220380D01*
X593460D01*
G01Y245380D02*
Y232880D01*
G01Y245380D02*
Y232880D01*
G01D02*
X621460D01*
G01X593460Y245380D02*
X621460D01*
G01X593460Y270380D02*
Y257880D01*
G01D02*
X621460D01*
G01X593460Y295380D02*
Y282880D01*
G01D02*
X621460D01*
G01X593460Y295380D02*
Y282880D01*
G01D02*
X621460D01*
G01X593460D02*
Y270380D01*
G01D02*
X621460D01*
G01X593460Y295380D02*
X621460D01*
G01X593460Y307880D02*
X621460D01*
G01X593460Y345380D02*
Y332880D01*
G01D02*
X621460D01*
G01X593460D02*
Y320380D01*
G01D02*
X621460D01*
G01X593460Y357880D02*
Y345380D01*
G01D02*
X621460D01*
G01X1246460Y357880D02*
X593460D01*
G01D02*
Y375380D01*
G01Y357880D02*
X1272960D01*
Y345380D01*
G01X593460Y375380D02*
X602460D01*
G01X1249610D02*
X593460D01*
G01X602460D02*
X1189160D01*
G01X621460Y207880D02*
Y332880D01*
G01D02*
Y345380D01*
G01D02*
X735460D01*
G01X621460D02*
Y357880D01*
G01D02*
Y375380D01*
G01X735460Y207880D02*
Y358380D01*
G01X1249610Y232880D02*
X735460D01*
G01X1249610Y245380D02*
X735460D01*
G01Y257880D02*
X1272960D01*
Y245380D01*
G01X1249610Y282880D02*
X735460D01*
G01X1249610D02*
X735460D01*
G01X1249610Y270380D02*
X735460D01*
G01Y295380D02*
X1272960D01*
Y282880D01*
G01X1249610Y307880D02*
X735460D01*
G01X1249610Y332880D02*
X735460D01*
G01Y320380D02*
X1272960D01*
Y307880D01*
G01X1249610Y345380D02*
X735460D01*
G01D02*
Y357880D01*
G01D02*
Y375380D01*
G01X1158110Y232880D02*
X1272960D01*
Y220380D01*
G01X1158110Y245380D02*
X1272960D01*
Y232880D01*
G01X1158110Y282880D02*
X1249610D01*
G01X1158110D02*
X1272960D01*
Y270380D01*
G01X1158110D02*
X1272960D01*
Y257880D01*
G01X1158110Y307880D02*
X1272960D01*
Y295380D01*
G01X1158110Y332880D02*
X1272960D01*
Y320380D01*
G01X1158110Y345380D02*
X1272960D01*
Y332880D01*
G01X1189260Y197780D02*
X1189160Y197880D01*
G01X1228260Y518680D02*
Y518780D01*
M02*
